FILE_TYPE = MACRO_DRAWING;
SET COLOR_WIRE YELLOW;
SET COLOR_PROP ORANGE;
SET COLOR_DOT WHITE;
SET COLOR_ARC YELLOW;
SET COLOR_BODY GREEN;
SET COLOR_NOTE PURPLE;
SET PROP_DISPLAY VALUE;
SET PAGE_NUMBER P162;
FORCEADD UNIVERSAL_GND..1
(-5025 -1000);
FORCEPROP 3 LASTPIN (-5025 -950) SIG_NAME GND\g
J 0
(-5015 -940);
DISPLAY 0.659574 (-5015 -940);
PAINT MONO (-5015 -940);
DISPLAY INVISIBLE (-5015 -940);
FORCEPROP 2 LAST CDS_LIB logical_power
J 0
(-5025 -1000);
DISPLAY INVISIBLE (-5025 -1000);
FORCEPROP 1 LAST HDL_POWER GND
J 1
(-5000 -1075);
DISPLAY 0.872340 (-5000 -1075);
PAINT GREEN (-5000 -1075);
DISPLAY INVISIBLE (-5000 -1075);
FORCEPROP 2 LAST ROOM IO_SLOT
J 1
(-5250 -925);
DISPLAY 0.744681 (-5250 -925);
DISPLAY INVISIBLE (-5250 -925);
FORCEPROP 1 LAST PATH I1
J 0
(-4950 -1000);
DISPLAY 0.872340 (-4950 -1000);
PAINT AQUA (-4950 -1000);
DISPLAY INVISIBLE (-4950 -1000);
FORCEADD UNIVERSAL_GND..1
(-5350 750);
FORCEPROP 3 LASTPIN (-5350 800) SIG_NAME GND\g
J 0
(-5340 810);
DISPLAY 0.659574 (-5340 810);
PAINT MONO (-5340 810);
DISPLAY INVISIBLE (-5340 810);
FORCEPROP 2 LAST CDS_LIB logical_power
J 0
(-5350 750);
DISPLAY INVISIBLE (-5350 750);
FORCEPROP 1 LAST HDL_POWER GND
J 1
(-5325 675);
DISPLAY 0.872340 (-5325 675);
PAINT GREEN (-5325 675);
DISPLAY INVISIBLE (-5325 675);
FORCEPROP 2 LAST ROOM IO_SLOT
J 1
(-5575 825);
DISPLAY 0.744681 (-5575 825);
DISPLAY INVISIBLE (-5575 825);
FORCEPROP 1 LAST PATH I10
J 0
(-5275 750);
DISPLAY 0.872340 (-5275 750);
PAINT AQUA (-5275 750);
DISPLAY INVISIBLE (-5275 750);
FORCEADD Q_RES..2
(-5350 1100);
FORCEPROP 1 LAST PART_NUMBER CS21002FB06
J 0
(-5310 975);
DISPLAY 0.638298 (-5310 975);
DISPLAY INVISIBLE (-5310 975);
FORCEPROP 1 LAST MATERIAL EMPTY
J 0
(-5310 1025);
DISPLAY 0.638298 (-5310 1025);
PAINT RED (-5310 1025);
FORCEPROP 1 LAST TOLERANCE 1%
J 0
(-5305 1125);
DISPLAY 0.638298 (-5305 1125);
FORCEPROP 1 LAST WATTAGE 1/16W
J 0
(-5310 1075);
DISPLAY 0.638298 (-5310 1075);
FORCEPROP 1 LAST VALUE 1K
J 0
(-5305 1175);
DISPLAY 0.638298 (-5305 1175);
FORCEPROP 1 LAST PACK_TYPE 0402LF
J 0
(-5310 925);
DISPLAY 0.638298 (-5310 925);
FORCEPROP 1 LAST $LOCATION R4274
J 0
(-5305 1225);
DISPLAY 0.978723 (-5305 1225);
FORCEPROP 1 LASTPIN (-5350 1200) $PN 1
J 0
(-5345 1162);
DISPLAY 0.787234 (-5345 1162);
PAINT MONO (-5345 1162);
FORCEPROP 1 LASTPIN (-5350 1000) $PN 2
J 0
(-5345 1010);
DISPLAY 0.787234 (-5345 1010);
PAINT MONO (-5345 1010);
FORCEPROP 2 LAST CDS_LIB pure_quanta
J 0
(-5350 1100);
DISPLAY INVISIBLE (-5350 1100);
FORCEPROP 1 LAST PATH I11
J 0
(-5300 1275);
DISPLAY 0.978723 (-5300 1275);
PAINT WHITE (-5300 1275);
DISPLAY INVISIBLE (-5300 1275);
FORCEPROP 0 LAST CDS_LOCATION R4274
J 0
(-5300 1275);
DISPLAY 1.021277 (-5300 1275);
DISPLAY INVISIBLE (-5300 1275);
FORCEPROP 0 LAST $SEC 1
J 0
(-5300 1275);
DISPLAY 0.680851 (-5300 1275);
PAINT MONO (-5300 1275);
DISPLAY INVISIBLE (-5300 1275);
FORCEPROP 0 LAST CDS_SEC 1
J 0
(-5300 1275);
DISPLAY 1.021277 (-5300 1275);
DISPLAY INVISIBLE (-5300 1275);
FORCEADD Q_RES..2
(-5350 1625);
FORCEPROP 1 LAST PART_NUMBER CS21002FB06
J 0
(-5310 1500);
DISPLAY 0.638298 (-5310 1500);
DISPLAY INVISIBLE (-5310 1500);
FORCEPROP 1 LAST WATTAGE 1/16W
J 0
(-5310 1600);
DISPLAY 0.638298 (-5310 1600);
FORCEPROP 1 LAST TOLERANCE 1%
J 0
(-5305 1650);
DISPLAY 0.638298 (-5305 1650);
FORCEPROP 1 LAST VALUE 1K
J 0
(-5305 1700);
DISPLAY 0.638298 (-5305 1700);
FORCEPROP 1 LAST PACK_TYPE 0402LF
J 0
(-5310 1450);
DISPLAY 0.638298 (-5310 1450);
FORCEPROP 1 LAST MATERIAL EMPTY
J 0
(-5310 1550);
DISPLAY 0.638298 (-5310 1550);
PAINT RED (-5310 1550);
FORCEPROP 1 LAST $LOCATION R4273
J 0
(-5305 1750);
DISPLAY 0.638298 (-5305 1750);
FORCEPROP 1 LASTPIN (-5350 1725) $PN 1
J 0
(-5345 1687);
DISPLAY 0.787234 (-5345 1687);
PAINT MONO (-5345 1687);
FORCEPROP 1 LASTPIN (-5350 1525) $PN 2
J 0
(-5345 1535);
DISPLAY 0.787234 (-5345 1535);
PAINT MONO (-5345 1535);
FORCEPROP 2 LAST CDS_LIB pure_quanta
J 0
(-5350 1625);
DISPLAY INVISIBLE (-5350 1625);
FORCEPROP 1 LAST PATH I12
J 0
(-5300 1800);
DISPLAY 0.978723 (-5300 1800);
PAINT WHITE (-5300 1800);
DISPLAY INVISIBLE (-5300 1800);
FORCEPROP 0 LAST CDS_LOCATION R4273
J 0
(-5300 1800);
DISPLAY 1.021277 (-5300 1800);
DISPLAY INVISIBLE (-5300 1800);
FORCEPROP 0 LAST $SEC 1
J 0
(-5300 1800);
DISPLAY 0.680851 (-5300 1800);
PAINT MONO (-5300 1800);
DISPLAY INVISIBLE (-5300 1800);
FORCEPROP 0 LAST CDS_SEC 1
J 0
(-5300 1800);
DISPLAY 1.021277 (-5300 1800);
DISPLAY INVISIBLE (-5300 1800);
FORCEADD UNIVERSAL_POWER..1
(-5350 1925);
FORCEPROP 3 LASTPIN (-5350 1875) SIG_NAME P3V3_AUX\g
J 0
(-5340 1885);
DISPLAY 0.659574 (-5340 1885);
PAINT MONO (-5340 1885);
DISPLAY INVISIBLE (-5340 1885);
FORCEPROP 1 LAST HDL_POWER P3V3_AUX
J 1
(-5350 1975);
DISPLAY 0.872340 (-5350 1975);
PAINT GREEN (-5350 1975);
FORCEPROP 2 LAST CDS_LIB logical_power
J 0
(-5350 1925);
DISPLAY INVISIBLE (-5350 1925);
FORCEPROP 1 LAST PATH I13
J 0
(-5300 1950);
DISPLAY 0.872340 (-5300 1950);
PAINT AQUA (-5300 1950);
DISPLAY INVISIBLE (-5300 1950);
FORCEADD OFFPAGE..4
R 2
(-4900 3175);
FORCEPROP 2 LAST $XR0 240 
J 0
(-5152 3175);
DISPLAY 0.638298 (-5152 3175);
PAINT MONO (-5152 3175);
FORCEPROP 2 LAST CDS_LIB standard
J 2
(-4900 3175);
DISPLAY INVISIBLE (-4900 3175);
FORCEPROP 1 LAST OFFPAGE TRUE
J 2
(-5225 3050);
DISPLAY 0.872340 (-5225 3050);
PAINT GREEN (-5225 3050);
DISPLAY INVISIBLE (-5225 3050);
FORCEPROP 1 LAST COMMENT_BODY TRUE
J 2
(-4875 3075);
DISPLAY 0.872340 (-4875 3075);
PAINT GREEN (-4875 3075);
DISPLAY INVISIBLE (-4875 3075);
FORCEPROP 2 LAST PATH I14
J 0
(-5150 3225);
DISPLAY 1.021277 (-5150 3225);
DISPLAY INVISIBLE (-5150 3225);
FORCEADD OFFPAGE..4
R 2
(-4900 3225);
FORCEPROP 2 LAST $XR0 240 
J 0
(-5152 3225);
DISPLAY 0.638298 (-5152 3225);
PAINT MONO (-5152 3225);
FORCEPROP 2 LAST CDS_LIB standard
J 0
(-4900 3225);
DISPLAY INVISIBLE (-4900 3225);
FORCEPROP 1 LAST OFFPAGE TRUE
J 2
(-5225 3100);
DISPLAY 0.872340 (-5225 3100);
PAINT GREEN (-5225 3100);
DISPLAY INVISIBLE (-5225 3100);
FORCEPROP 1 LAST COMMENT_BODY TRUE
J 2
(-4875 3125);
DISPLAY 0.872340 (-4875 3125);
PAINT GREEN (-4875 3125);
DISPLAY INVISIBLE (-4875 3125);
FORCEPROP 2 LAST PATH I15
J 0
(-5150 3275);
DISPLAY 1.021277 (-5150 3275);
DISPLAY INVISIBLE (-5150 3275);
FORCEADD UNIVERSAL_GND..1
(-4475 750);
FORCEPROP 3 LASTPIN (-4475 800) SIG_NAME GND\g
J 0
(-4465 810);
DISPLAY 0.659574 (-4465 810);
PAINT MONO (-4465 810);
DISPLAY INVISIBLE (-4465 810);
FORCEPROP 2 LAST CDS_LIB logical_power
J 0
(-4475 750);
DISPLAY INVISIBLE (-4475 750);
FORCEPROP 2 LAST ROOM IO_SLOT
J 1
(-4700 825);
DISPLAY 0.744681 (-4700 825);
DISPLAY INVISIBLE (-4700 825);
FORCEPROP 1 LAST HDL_POWER GND
J 1
(-4450 675);
DISPLAY 0.872340 (-4450 675);
PAINT GREEN (-4450 675);
DISPLAY INVISIBLE (-4450 675);
FORCEPROP 1 LAST PATH I16
J 0
(-4400 750);
DISPLAY 0.872340 (-4400 750);
PAINT AQUA (-4400 750);
DISPLAY INVISIBLE (-4400 750);
FORCEADD Q_RES..2
(-4475 1050);
FORCEPROP 1 LAST PART_NUMBER CS21002FB06
J 0
(-4435 925);
DISPLAY 0.638298 (-4435 925);
DISPLAY INVISIBLE (-4435 925);
FORCEPROP 1 LAST PACK_TYPE 0402LF
J 0
(-4435 875);
DISPLAY 0.638298 (-4435 875);
FORCEPROP 1 LAST MATERIAL EMPTY
J 0
(-4435 975);
DISPLAY 0.638298 (-4435 975);
PAINT RED (-4435 975);
FORCEPROP 1 LAST WATTAGE 1/16W
J 0
(-4435 1025);
DISPLAY 0.638298 (-4435 1025);
FORCEPROP 1 LAST TOLERANCE 1%
J 0
(-4430 1075);
DISPLAY 0.638298 (-4430 1075);
FORCEPROP 1 LAST VALUE 1K
J 0
(-4430 1125);
DISPLAY 0.638298 (-4430 1125);
FORCEPROP 1 LAST $LOCATION R4280
J 0
(-4430 1175);
DISPLAY 0.978723 (-4430 1175);
FORCEPROP 1 LASTPIN (-4475 1150) $PN 1
J 0
(-4470 1112);
DISPLAY 0.787234 (-4470 1112);
PAINT MONO (-4470 1112);
FORCEPROP 1 LASTPIN (-4475 950) $PN 2
J 0
(-4470 960);
DISPLAY 0.787234 (-4470 960);
PAINT MONO (-4470 960);
FORCEPROP 2 LAST CDS_LIB pure_quanta
J 0
(-4475 1050);
DISPLAY INVISIBLE (-4475 1050);
FORCEPROP 1 LAST PATH I17
J 0
(-4425 1225);
DISPLAY 0.978723 (-4425 1225);
PAINT WHITE (-4425 1225);
DISPLAY INVISIBLE (-4425 1225);
FORCEPROP 0 LAST CDS_LOCATION R4280
J 0
(-4425 1225);
DISPLAY 1.021277 (-4425 1225);
DISPLAY INVISIBLE (-4425 1225);
FORCEPROP 0 LAST $SEC 1
J 0
(-4425 1225);
DISPLAY 0.680851 (-4425 1225);
PAINT MONO (-4425 1225);
DISPLAY INVISIBLE (-4425 1225);
FORCEPROP 0 LAST CDS_SEC 1
J 0
(-4425 1225);
DISPLAY 1.021277 (-4425 1225);
DISPLAY INVISIBLE (-4425 1225);
FORCEADD Q_RES..2
(-4475 1625);
FORCEPROP 1 LAST PART_NUMBER CS21002FB06
J 0
(-4435 1500);
DISPLAY 0.638298 (-4435 1500);
DISPLAY INVISIBLE (-4435 1500);
FORCEPROP 1 LAST WATTAGE 1/16W
J 0
(-4435 1600);
DISPLAY 0.638298 (-4435 1600);
FORCEPROP 1 LAST PACK_TYPE 0402LF
J 0
(-4435 1450);
DISPLAY 0.638298 (-4435 1450);
FORCEPROP 1 LAST VALUE 1K
J 0
(-4430 1700);
DISPLAY 0.638298 (-4430 1700);
FORCEPROP 1 LAST TOLERANCE 1%
J 0
(-4430 1650);
DISPLAY 0.638298 (-4430 1650);
FORCEPROP 1 LAST MATERIAL EMPTY
J 0
(-4435 1550);
DISPLAY 0.638298 (-4435 1550);
PAINT RED (-4435 1550);
FORCEPROP 1 LAST $LOCATION R4279
J 0
(-4430 1750);
DISPLAY 0.978723 (-4430 1750);
FORCEPROP 1 LASTPIN (-4475 1725) $PN 1
J 0
(-4470 1687);
DISPLAY 0.787234 (-4470 1687);
PAINT MONO (-4470 1687);
FORCEPROP 1 LASTPIN (-4475 1525) $PN 2
J 0
(-4470 1535);
DISPLAY 0.787234 (-4470 1535);
PAINT MONO (-4470 1535);
FORCEPROP 2 LAST CDS_LIB pure_quanta
J 0
(-4475 1625);
DISPLAY INVISIBLE (-4475 1625);
FORCEPROP 1 LAST PATH I18
J 0
(-4425 1800);
DISPLAY 0.978723 (-4425 1800);
PAINT WHITE (-4425 1800);
DISPLAY INVISIBLE (-4425 1800);
FORCEPROP 0 LAST CDS_LOCATION R4279
J 0
(-4425 1800);
DISPLAY 1.021277 (-4425 1800);
DISPLAY INVISIBLE (-4425 1800);
FORCEPROP 0 LAST $SEC 1
J 0
(-4425 1800);
DISPLAY 0.680851 (-4425 1800);
PAINT MONO (-4425 1800);
DISPLAY INVISIBLE (-4425 1800);
FORCEPROP 0 LAST CDS_SEC 1
J 0
(-4425 1800);
DISPLAY 1.021277 (-4425 1800);
DISPLAY INVISIBLE (-4425 1800);
FORCEADD OFFPAGE..2
(-3925 1325);
FORCEPROP 2 LAST $XR0 169 
J 0
(-3736 1325);
DISPLAY 0.638298 (-3736 1325);
PAINT MONO (-3736 1325);
FORCEPROP 2 LAST CDS_LIB standard
J 0
(-3925 1325);
DISPLAY INVISIBLE (-3925 1325);
FORCEPROP 1 LAST OFFPAGE TRUE
J 0
(-3600 1200);
DISPLAY 0.872340 (-3600 1200);
PAINT GREEN (-3600 1200);
DISPLAY INVISIBLE (-3600 1200);
FORCEPROP 1 LAST COMMENT_BODY TRUE
J 0
(-3970 1230);
DISPLAY 0.872340 (-3970 1230);
PAINT GREEN (-3970 1230);
DISPLAY INVISIBLE (-3970 1230);
FORCEPROP 2 LAST PATH I19
J 0
(-3725 1375);
DISPLAY 1.021277 (-3725 1375);
DISPLAY INVISIBLE (-3725 1375);
FORCEADD Q_RES..2
(-5025 -650);
FORCEPROP 1 LAST PART_NUMBER CS36802FB04
J 0
(-4985 -775);
DISPLAY 0.638298 (-4985 -775);
DISPLAY INVISIBLE (-4985 -775);
FORCEPROP 1 LAST VALUE 68K
J 0
(-4980 -575);
DISPLAY 0.638298 (-4980 -575);
FORCEPROP 1 LAST TOLERANCE 1%
J 0
(-4980 -625);
DISPLAY 0.638298 (-4980 -625);
FORCEPROP 1 LAST PACK_TYPE 0402LF
J 0
(-4985 -825);
DISPLAY 0.638298 (-4985 -825);
FORCEPROP 1 LAST MATERIAL CHIP
J 0
(-4985 -725);
DISPLAY 0.638298 (-4985 -725);
FORCEPROP 1 LAST WATTAGE 1/16W
J 0
(-4985 -675);
DISPLAY 0.638298 (-4985 -675);
FORCEPROP 1 LAST LOCATION R4276
J 0
(-4980 -525);
DISPLAY 0.978723 (-4980 -525);
FORCEPROP 1 LASTPIN (-5025 -550) $PN 1
J 0
(-5020 -588);
DISPLAY 0.787234 (-5020 -588);
PAINT MONO (-5020 -588);
FORCEPROP 1 LASTPIN (-5025 -750) $PN 2
J 0
(-5020 -740);
DISPLAY 0.787234 (-5020 -740);
PAINT MONO (-5020 -740);
FORCEPROP 2 LAST CDS_LIB pure_quanta
J 0
(-5025 -650);
DISPLAY INVISIBLE (-5025 -650);
FORCEPROP 1 LAST PATH I2
J 0
(-4975 -475);
DISPLAY 0.978723 (-4975 -475);
PAINT WHITE (-4975 -475);
DISPLAY INVISIBLE (-4975 -475);
FORCEPROP 0 LAST $SEC 1
J 0
(-4975 -475);
DISPLAY 0.680851 (-4975 -475);
PAINT MONO (-4975 -475);
DISPLAY INVISIBLE (-4975 -475);
FORCEPROP 0 LAST CDS_SEC 1
J 0
(-4975 -475);
DISPLAY 1.021277 (-4975 -475);
DISPLAY INVISIBLE (-4975 -475);
FORCEADD OFFPAGE..2
(-3925 1375);
FORCEPROP 2 LAST $XR0 169 
J 0
(-3736 1375);
DISPLAY 0.638298 (-3736 1375);
PAINT MONO (-3736 1375);
FORCEPROP 2 LAST CDS_LIB standard
J 0
(-3925 1375);
DISPLAY INVISIBLE (-3925 1375);
FORCEPROP 1 LAST OFFPAGE TRUE
J 0
(-3600 1250);
DISPLAY 0.872340 (-3600 1250);
PAINT GREEN (-3600 1250);
DISPLAY INVISIBLE (-3600 1250);
FORCEPROP 1 LAST COMMENT_BODY TRUE
J 0
(-3970 1280);
DISPLAY 0.872340 (-3970 1280);
PAINT GREEN (-3970 1280);
DISPLAY INVISIBLE (-3970 1280);
FORCEPROP 2 LAST PATH I20
J 0
(-3725 1425);
DISPLAY 1.021277 (-3725 1425);
DISPLAY INVISIBLE (-3725 1425);
FORCEADD UNIVERSAL_GND..1
(-3850 2600);
FORCEPROP 3 LASTPIN (-3850 2650) SIG_NAME GND\g
J 0
(-3840 2660);
DISPLAY 0.659574 (-3840 2660);
PAINT MONO (-3840 2660);
DISPLAY INVISIBLE (-3840 2660);
FORCEPROP 1 LAST HDL_POWER GND
J 1
(-3825 2525);
DISPLAY 0.872340 (-3825 2525);
PAINT GREEN (-3825 2525);
DISPLAY INVISIBLE (-3825 2525);
FORCEPROP 2 LAST ROOM IO_SLOT
J 1
(-4075 2675);
DISPLAY 0.744681 (-4075 2675);
DISPLAY INVISIBLE (-4075 2675);
FORCEPROP 2 LAST CDS_LIB logical_power
J 0
(-3850 2600);
DISPLAY INVISIBLE (-3850 2600);
FORCEPROP 1 LAST PATH I21
J 0
(-3775 2600);
DISPLAY 0.872340 (-3775 2600);
PAINT AQUA (-3775 2600);
DISPLAY INVISIBLE (-3775 2600);
FORCEADD UNIVERSAL_GND..1
(-4250 2600);
FORCEPROP 3 LASTPIN (-4250 2650) SIG_NAME GND\g
J 0
(-4240 2660);
DISPLAY 0.659574 (-4240 2660);
PAINT MONO (-4240 2660);
DISPLAY INVISIBLE (-4240 2660);
FORCEPROP 2 LAST CDS_LIB logical_power
J 0
(-4250 2600);
DISPLAY INVISIBLE (-4250 2600);
FORCEPROP 1 LAST HDL_POWER GND
J 1
(-4225 2525);
DISPLAY 0.872340 (-4225 2525);
PAINT GREEN (-4225 2525);
DISPLAY INVISIBLE (-4225 2525);
FORCEPROP 2 LAST ROOM IO_SLOT
J 1
(-4475 2675);
DISPLAY 0.744681 (-4475 2675);
DISPLAY INVISIBLE (-4475 2675);
FORCEPROP 1 LAST PATH I22
J 0
(-4175 2600);
DISPLAY 0.872340 (-4175 2600);
PAINT AQUA (-4175 2600);
DISPLAY INVISIBLE (-4175 2600);
FORCEADD Q_RES..2
(-4250 2900);
FORCEPROP 1 LAST PART_NUMBER CS42002FB05
J 0
(-4210 2775);
DISPLAY 0.638298 (-4210 2775);
DISPLAY INVISIBLE (-4210 2775);
FORCEPROP 1 LAST MATERIAL CHIP
J 0
(-4210 2825);
DISPLAY 0.638298 (-4210 2825);
FORCEPROP 1 LAST PACK_TYPE 0402LF
J 0
(-4210 2725);
DISPLAY 0.638298 (-4210 2725);
FORCEPROP 1 LAST VALUE 200K
J 0
(-4205 2975);
DISPLAY 0.638298 (-4205 2975);
FORCEPROP 1 LAST WATTAGE 1/16W
J 0
(-4210 2875);
DISPLAY 0.638298 (-4210 2875);
FORCEPROP 1 LAST TOLERANCE 1%
J 0
(-4205 2925);
DISPLAY 0.638298 (-4205 2925);
FORCEPROP 1 LAST $LOCATION R4636
J 0
(-4205 3025);
DISPLAY 0.808511 (-4205 3025);
FORCEPROP 1 LASTPIN (-4250 3000) $PN 1
J 0
(-4245 2962);
DISPLAY 0.787234 (-4245 2962);
PAINT MONO (-4245 2962);
FORCEPROP 1 LASTPIN (-4250 2800) $PN 2
J 0
(-4245 2810);
DISPLAY 0.787234 (-4245 2810);
PAINT MONO (-4245 2810);
FORCEPROP 2 LAST CDS_LIB pure_quanta
J 0
(-4250 2900);
DISPLAY INVISIBLE (-4250 2900);
FORCEPROP 1 LAST PATH I23
J 0
(-4200 3075);
DISPLAY 0.978723 (-4200 3075);
PAINT WHITE (-4200 3075);
DISPLAY INVISIBLE (-4200 3075);
FORCEPROP 0 LAST CDS_LOCATION R4636
J 0
(-4200 3075);
DISPLAY 1.021277 (-4200 3075);
DISPLAY INVISIBLE (-4200 3075);
FORCEPROP 0 LAST $SEC 1
J 0
(-4200 3075);
DISPLAY 0.680851 (-4200 3075);
PAINT MONO (-4200 3075);
DISPLAY INVISIBLE (-4200 3075);
FORCEPROP 0 LAST CDS_SEC 1
J 0
(-4200 3075);
DISPLAY 1.021277 (-4200 3075);
DISPLAY INVISIBLE (-4200 3075);
FORCEADD Q_RES..2
(-3850 2900);
FORCEPROP 1 LAST PART_NUMBER CS42002FB05
J 0
(-3810 2775);
DISPLAY 0.638298 (-3810 2775);
DISPLAY INVISIBLE (-3810 2775);
FORCEPROP 1 LAST PACK_TYPE 0402LF
J 0
(-3810 2725);
DISPLAY 0.638298 (-3810 2725);
FORCEPROP 1 LAST TOLERANCE 1%
J 0
(-3805 2925);
DISPLAY 0.638298 (-3805 2925);
FORCEPROP 1 LAST VALUE 200K
J 0
(-3805 2975);
DISPLAY 0.638298 (-3805 2975);
FORCEPROP 1 LAST WATTAGE 1/16W
J 0
(-3810 2875);
DISPLAY 0.638298 (-3810 2875);
FORCEPROP 1 LAST MATERIAL CHIP
J 0
(-3810 2825);
DISPLAY 0.638298 (-3810 2825);
FORCEPROP 1 LAST $LOCATION R4637
J 0
(-3805 3025);
DISPLAY 0.787234 (-3805 3025);
FORCEPROP 1 LASTPIN (-3850 3000) $PN 1
J 0
(-3845 2962);
DISPLAY 0.787234 (-3845 2962);
PAINT MONO (-3845 2962);
FORCEPROP 1 LASTPIN (-3850 2800) $PN 2
J 0
(-3845 2810);
DISPLAY 0.787234 (-3845 2810);
PAINT MONO (-3845 2810);
FORCEPROP 2 LAST CDS_LIB pure_quanta
J 0
(-3850 2900);
DISPLAY INVISIBLE (-3850 2900);
FORCEPROP 1 LAST PATH I24
J 0
(-3800 3075);
DISPLAY 0.978723 (-3800 3075);
PAINT WHITE (-3800 3075);
DISPLAY INVISIBLE (-3800 3075);
FORCEPROP 0 LAST CDS_LOCATION R4637
J 0
(-3800 3075);
DISPLAY 1.021277 (-3800 3075);
DISPLAY INVISIBLE (-3800 3075);
FORCEPROP 0 LAST $SEC 1
J 0
(-3800 3075);
DISPLAY 0.680851 (-3800 3075);
PAINT MONO (-3800 3075);
DISPLAY INVISIBLE (-3800 3075);
FORCEPROP 0 LAST CDS_SEC 1
J 0
(-3800 3075);
DISPLAY 1.021277 (-3800 3075);
DISPLAY INVISIBLE (-3800 3075);
FORCEADD Q_CAP_DIFFBUS..2
(-3725 3175);
FORCEPROP 1 LAST PART_NUMBER SP_CH4331KEB01
J 0
(-3759 3288);
DISPLAY 0.723404 (-3759 3288);
PAINT GREEN (-3759 3288);
DISPLAY INVISIBLE (-3759 3288);
FORCEPROP 2 LAST PACK_TYPE C0402
J 0
(-3600 3175);
DISPLAY 0.404255 (-3600 3175);
FORCEPROP 2 LAST TOLERANCE 10%
J 0
(-3150 3175);
DISPLAY 0.404255 (-3150 3175);
FORCEPROP 2 LAST VALUE DIFF BUS_0.33UF
J 0
(-3475 3175);
DISPLAY 0.404255 (-3475 3175);
FORCEPROP 1 LAST LOCATION C2350
J 0
(-4000 3175);
DISPLAY 0.723404 (-4000 3175);
PAINT GREEN (-4000 3175);
FORCEPROP 0 LASTPIN (-3800 3175) $PN 1
J 2
(-3810 3185);
DISPLAY 0.680851 (-3810 3185);
PAINT MONO (-3810 3185);
FORCEPROP 0 LASTPIN (-3650 3175) $PN 2
J 0
(-3640 3185);
DISPLAY 0.680851 (-3640 3185);
PAINT MONO (-3640 3185);
FORCEPROP 0 LAST VOLTAGE 6.3V
J 0
(-3650 3350);
DISPLAY 1.021277 (-3650 3350);
DISPLAY INVISIBLE (-3650 3350);
FORCEPROP 1 LAST MATERIAL X6S
J 0
(-3759 3229);
DISPLAY 0.723404 (-3759 3229);
PAINT GREEN (-3759 3229);
DISPLAY INVISIBLE (-3759 3229);
FORCEPROP 1 LAST CDS_LMAN_SYM_OUTLINE -25,50,25,-50
J 0
(-3725 3175);
DISPLAY 0.468085 (-3725 3175);
PAINT GREEN (-3725 3175);
DISPLAY INVISIBLE (-3725 3175);
FORCEPROP 1 LAST PIN_NAMES_ROTATE True
J 0
(-3725 3175);
DISPLAY 0.489362 (-3725 3175);
PAINT GREEN (-3725 3175);
DISPLAY INVISIBLE (-3725 3175);
FORCEPROP 2 LAST CDS_LIB pure_quanta
J 0
(-3725 3175);
DISPLAY INVISIBLE (-3725 3175);
FORCEPROP 1 LAST PATH I25
J 0
(-3725 3175);
DISPLAY 0.723404 (-3725 3175);
DISPLAY INVISIBLE (-3725 3175);
FORCEPROP 0 LAST $SEC 1
J 0
(-4000 3225);
DISPLAY 0.680851 (-4000 3225);
PAINT MONO (-4000 3225);
DISPLAY INVISIBLE (-4000 3225);
FORCEPROP 0 LAST CDS_SEC 1
J 0
(-4000 3225);
DISPLAY 1.021277 (-4000 3225);
DISPLAY INVISIBLE (-4000 3225);
FORCEADD Q_CAP_DIFFBUS..2
(-3725 3225);
FORCEPROP 1 LAST PART_NUMBER SP_CH4331KEB01
J 0
(-3759 3338);
DISPLAY 0.723404 (-3759 3338);
PAINT GREEN (-3759 3338);
DISPLAY INVISIBLE (-3759 3338);
FORCEPROP 2 LAST VALUE DIFF BUS_0.33UF
J 0
(-3475 3225);
DISPLAY 0.404255 (-3475 3225);
FORCEPROP 2 LAST TOLERANCE 10%
J 0
(-3150 3225);
DISPLAY 0.404255 (-3150 3225);
FORCEPROP 2 LAST PACK_TYPE C0402
J 0
(-3600 3225);
DISPLAY 0.404255 (-3600 3225);
FORCEPROP 1 LAST LOCATION C2349
J 0
(-4000 3225);
DISPLAY 0.723404 (-4000 3225);
PAINT GREEN (-4000 3225);
FORCEPROP 0 LASTPIN (-3800 3225) $PN 1
J 2
(-3810 3235);
DISPLAY 0.680851 (-3810 3235);
PAINT MONO (-3810 3235);
FORCEPROP 0 LASTPIN (-3650 3225) $PN 2
J 0
(-3640 3235);
DISPLAY 0.680851 (-3640 3235);
PAINT MONO (-3640 3235);
FORCEPROP 2 LAST CDS_LIB pure_quanta
J 0
(-3725 3225);
DISPLAY INVISIBLE (-3725 3225);
FORCEPROP 1 LAST CDS_LMAN_SYM_OUTLINE -25,50,25,-50
J 0
(-3725 3225);
DISPLAY 0.468085 (-3725 3225);
PAINT GREEN (-3725 3225);
DISPLAY INVISIBLE (-3725 3225);
FORCEPROP 0 LAST VOLTAGE 6.3V
J 0
(-3650 3400);
DISPLAY 1.021277 (-3650 3400);
DISPLAY INVISIBLE (-3650 3400);
FORCEPROP 1 LAST MATERIAL X6S
J 0
(-3759 3279);
DISPLAY 0.723404 (-3759 3279);
PAINT GREEN (-3759 3279);
DISPLAY INVISIBLE (-3759 3279);
FORCEPROP 1 LAST PIN_NAMES_ROTATE True
J 0
(-3725 3225);
DISPLAY 0.489362 (-3725 3225);
PAINT GREEN (-3725 3225);
DISPLAY INVISIBLE (-3725 3225);
FORCEPROP 1 LAST PATH I26
J 0
(-3725 3225);
DISPLAY 0.723404 (-3725 3225);
DISPLAY INVISIBLE (-3725 3225);
FORCEPROP 0 LAST $SEC 1
J 0
(-4000 3275);
DISPLAY 0.680851 (-4000 3275);
PAINT MONO (-4000 3275);
DISPLAY INVISIBLE (-4000 3275);
FORCEPROP 0 LAST CDS_SEC 1
J 0
(-4000 3275);
DISPLAY 1.021277 (-4000 3275);
DISPLAY INVISIBLE (-4000 3275);
FORCEADD OFFPAGE..4
R 2
(-3250 3325);
FORCEPROP 2 LAST $XR0 181 
J 0
(-3532 3325);
DISPLAY 0.638298 (-3532 3325);
PAINT MONO (-3532 3325);
FORCEPROP 2 LAST CDS_LIB standard
J 0
(-3250 3325);
DISPLAY INVISIBLE (-3250 3325);
FORCEPROP 1 LAST OFFPAGE TRUE
J 2
(-3575 3200);
DISPLAY 0.872340 (-3575 3200);
PAINT GREEN (-3575 3200);
DISPLAY INVISIBLE (-3575 3200);
FORCEPROP 1 LAST COMMENT_BODY TRUE
J 2
(-3225 3225);
DISPLAY 0.872340 (-3225 3225);
PAINT GREEN (-3225 3225);
DISPLAY INVISIBLE (-3225 3225);
FORCEPROP 2 LAST PATH I27
J 0
(-3525 3375);
DISPLAY 1.021277 (-3525 3375);
DISPLAY INVISIBLE (-3525 3375);
FORCEADD OFFPAGE..4
R 2
(-3250 3375);
FORCEPROP 2 LAST $XR0 181 
J 0
(-3532 3375);
DISPLAY 0.638298 (-3532 3375);
PAINT MONO (-3532 3375);
FORCEPROP 2 LAST CDS_LIB standard
J 0
(-3250 3375);
DISPLAY INVISIBLE (-3250 3375);
FORCEPROP 1 LAST OFFPAGE TRUE
J 2
(-3575 3250);
DISPLAY 0.872340 (-3575 3250);
PAINT GREEN (-3575 3250);
DISPLAY INVISIBLE (-3575 3250);
FORCEPROP 1 LAST COMMENT_BODY TRUE
J 2
(-3225 3275);
DISPLAY 0.872340 (-3225 3275);
PAINT GREEN (-3225 3275);
DISPLAY INVISIBLE (-3225 3275);
FORCEPROP 2 LAST PATH I28
J 0
(-3525 3425);
DISPLAY 1.021277 (-3525 3425);
DISPLAY INVISIBLE (-3525 3425);
FORCEADD OFFPAGE..4
R 2
(-3250 3575);
FORCEPROP 2 LAST $XR0 169 
J 0
(-3532 3575);
DISPLAY 0.638298 (-3532 3575);
PAINT MONO (-3532 3575);
FORCEPROP 2 LAST CDS_LIB standard
J 0
(-3250 3575);
DISPLAY INVISIBLE (-3250 3575);
FORCEPROP 1 LAST OFFPAGE TRUE
J 2
(-3575 3450);
DISPLAY 0.872340 (-3575 3450);
PAINT GREEN (-3575 3450);
DISPLAY INVISIBLE (-3575 3450);
FORCEPROP 1 LAST COMMENT_BODY TRUE
J 2
(-3225 3475);
DISPLAY 0.872340 (-3225 3475);
PAINT GREEN (-3225 3475);
DISPLAY INVISIBLE (-3225 3475);
FORCEPROP 2 LAST PATH I29
J 0
(-3525 3625);
DISPLAY 1.021277 (-3525 3625);
DISPLAY INVISIBLE (-3525 3625);
FORCEADD Q_RES..2
(-5025 -125);
FORCEPROP 1 LAST PART_NUMBER CS21002FB06
J 0
(-4985 -250);
DISPLAY 0.638298 (-4985 -250);
DISPLAY INVISIBLE (-4985 -250);
FORCEPROP 1 LAST MATERIAL EMPTY
J 0
(-4985 -200);
DISPLAY 0.638298 (-4985 -200);
PAINT RED (-4985 -200);
FORCEPROP 1 LAST VALUE 1K
J 0
(-4980 -50);
DISPLAY 0.638298 (-4980 -50);
FORCEPROP 1 LAST TOLERANCE 1%
J 0
(-4980 -100);
DISPLAY 0.638298 (-4980 -100);
FORCEPROP 1 LAST WATTAGE 1/16W
J 0
(-4985 -150);
DISPLAY 0.638298 (-4985 -150);
FORCEPROP 1 LAST PACK_TYPE 0402LF
J 0
(-4985 -300);
DISPLAY 0.638298 (-4985 -300);
FORCEPROP 1 LAST $LOCATION R4275
J 0
(-4980 0);
DISPLAY 0.638298 (-4980 0);
FORCEPROP 1 LASTPIN (-5025 -25) $PN 1
J 0
(-5020 -63);
DISPLAY 0.787234 (-5020 -63);
PAINT MONO (-5020 -63);
FORCEPROP 1 LASTPIN (-5025 -225) $PN 2
J 0
(-5020 -215);
DISPLAY 0.787234 (-5020 -215);
PAINT MONO (-5020 -215);
FORCEPROP 2 LAST CDS_LIB pure_quanta
J 0
(-5025 -125);
DISPLAY INVISIBLE (-5025 -125);
FORCEPROP 1 LAST PATH I3
J 0
(-4975 50);
DISPLAY 0.978723 (-4975 50);
PAINT WHITE (-4975 50);
DISPLAY INVISIBLE (-4975 50);
FORCEPROP 0 LAST CDS_LOCATION R4275
J 0
(-4975 50);
DISPLAY 1.021277 (-4975 50);
DISPLAY INVISIBLE (-4975 50);
FORCEPROP 0 LAST $SEC 1
J 0
(-4975 50);
DISPLAY 0.680851 (-4975 50);
PAINT MONO (-4975 50);
DISPLAY INVISIBLE (-4975 50);
FORCEPROP 0 LAST CDS_SEC 1
J 0
(-4975 50);
DISPLAY 1.021277 (-4975 50);
DISPLAY INVISIBLE (-4975 50);
FORCEADD OFFPAGE..4
R 2
(-3250 3525);
FORCEPROP 2 LAST $XR0 169 
J 0
(-3532 3525);
DISPLAY 0.638298 (-3532 3525);
PAINT MONO (-3532 3525);
FORCEPROP 2 LAST CDS_LIB standard
J 0
(-3250 3525);
DISPLAY INVISIBLE (-3250 3525);
FORCEPROP 1 LAST OFFPAGE TRUE
J 2
(-3575 3400);
DISPLAY 0.872340 (-3575 3400);
PAINT GREEN (-3575 3400);
DISPLAY INVISIBLE (-3575 3400);
FORCEPROP 1 LAST COMMENT_BODY TRUE
J 2
(-3225 3425);
DISPLAY 0.872340 (-3225 3425);
PAINT GREEN (-3225 3425);
DISPLAY INVISIBLE (-3225 3425);
FORCEPROP 2 LAST PATH I30
J 0
(-3525 3575);
DISPLAY 1.021277 (-3525 3575);
DISPLAY INVISIBLE (-3525 3575);
FORCEADD OFFPAGE..4
R 2
(-3250 3675);
FORCEPROP 2 LAST $XR0 169 
J 0
(-3532 3675);
DISPLAY 0.638298 (-3532 3675);
PAINT MONO (-3532 3675);
FORCEPROP 2 LAST CDS_LIB standard
J 0
(-3250 3675);
DISPLAY INVISIBLE (-3250 3675);
FORCEPROP 1 LAST OFFPAGE TRUE
J 2
(-3575 3550);
DISPLAY 0.872340 (-3575 3550);
PAINT GREEN (-3575 3550);
DISPLAY INVISIBLE (-3575 3550);
FORCEPROP 1 LAST COMMENT_BODY TRUE
J 2
(-3225 3575);
DISPLAY 0.872340 (-3225 3575);
PAINT GREEN (-3225 3575);
DISPLAY INVISIBLE (-3225 3575);
FORCEPROP 2 LAST PATH I31
J 0
(-3525 3725);
DISPLAY 1.021277 (-3525 3725);
DISPLAY INVISIBLE (-3525 3725);
FORCEADD OFFPAGE..4
R 2
(-3250 3825);
FORCEPROP 2 LAST $XR0 169 
J 0
(-3532 3825);
DISPLAY 0.638298 (-3532 3825);
PAINT MONO (-3532 3825);
FORCEPROP 2 LAST CDS_LIB standard
J 0
(-3250 3825);
DISPLAY INVISIBLE (-3250 3825);
FORCEPROP 1 LAST OFFPAGE TRUE
J 2
(-3575 3700);
DISPLAY 0.872340 (-3575 3700);
PAINT GREEN (-3575 3700);
DISPLAY INVISIBLE (-3575 3700);
FORCEPROP 1 LAST COMMENT_BODY TRUE
J 2
(-3225 3725);
DISPLAY 0.872340 (-3225 3725);
PAINT GREEN (-3225 3725);
DISPLAY INVISIBLE (-3225 3725);
FORCEPROP 2 LAST PATH I32
J 0
(-3525 3875);
DISPLAY 1.021277 (-3525 3875);
DISPLAY INVISIBLE (-3525 3875);
FORCEADD OFFPAGE..4
R 2
(-3250 3875);
FORCEPROP 2 LAST $XR0 169 
J 0
(-3532 3875);
DISPLAY 0.638298 (-3532 3875);
PAINT MONO (-3532 3875);
FORCEPROP 2 LAST CDS_LIB standard
J 0
(-3250 3875);
DISPLAY INVISIBLE (-3250 3875);
FORCEPROP 1 LAST OFFPAGE TRUE
J 2
(-3575 3750);
DISPLAY 0.872340 (-3575 3750);
PAINT GREEN (-3575 3750);
DISPLAY INVISIBLE (-3575 3750);
FORCEPROP 1 LAST COMMENT_BODY TRUE
J 2
(-3225 3775);
DISPLAY 0.872340 (-3225 3775);
PAINT GREEN (-3225 3775);
DISPLAY INVISIBLE (-3225 3775);
FORCEPROP 2 LAST PATH I33
J 0
(-3525 3925);
DISPLAY 1.021277 (-3525 3925);
DISPLAY INVISIBLE (-3525 3925);
FORCEADD OFFPAGE..4
R 2
(-3250 3725);
FORCEPROP 2 LAST $XR0 169 
J 0
(-3532 3725);
DISPLAY 0.638298 (-3532 3725);
PAINT MONO (-3532 3725);
FORCEPROP 2 LAST CDS_LIB standard
J 0
(-3250 3725);
DISPLAY INVISIBLE (-3250 3725);
FORCEPROP 1 LAST OFFPAGE TRUE
J 2
(-3575 3600);
DISPLAY 0.872340 (-3575 3600);
PAINT GREEN (-3575 3600);
DISPLAY INVISIBLE (-3575 3600);
FORCEPROP 1 LAST COMMENT_BODY TRUE
J 2
(-3225 3625);
DISPLAY 0.872340 (-3225 3625);
PAINT GREEN (-3225 3625);
DISPLAY INVISIBLE (-3225 3625);
FORCEPROP 2 LAST PATH I34
J 0
(-3525 3775);
DISPLAY 1.021277 (-3525 3775);
DISPLAY INVISIBLE (-3525 3775);
FORCEADD Q_INDUCTOR..1
(-3300 4650);
FORCEPROP 1 LAST PART_NUMBER CX5PX121001
J 0
(-3425 4760);
DISPLAY 0.574468 (-3425 4760);
PAINT GREEN (-3425 4760);
DISPLAY INVISIBLE (-3425 4760);
FORCEPROP 1 LAST MATERIAL IND
J 0
(-3425 4705);
DISPLAY 0.574468 (-3425 4705);
PAINT GREEN (-3425 4705);
FORCEPROP 2 LAST VALUE BLM15PX121SN1D/2A
J 0
(-3425 4900);
DISPLAY 0.808511 (-3425 4900);
FORCEPROP 2 LAST PACK_TYPE SMLF
J 0
(-3425 4850);
DISPLAY 0.808511 (-3425 4850);
FORCEPROP 1 LAST $LOCATION L18
J 0
(-3425 4810);
DISPLAY 0.574468 (-3425 4810);
PAINT GREEN (-3425 4810);
FORCEPROP 0 LASTPIN (-3400 4625) $PN 1
J 2
(-3410 4635);
DISPLAY 0.680851 (-3410 4635);
PAINT MONO (-3410 4635);
FORCEPROP 0 LASTPIN (-3200 4625) $PN 2
J 0
(-3190 4635);
DISPLAY 0.680851 (-3190 4635);
PAINT MONO (-3190 4635);
FORCEPROP 2 LAST CDS_LIB pure_quanta
J 0
(-3300 4650);
DISPLAY INVISIBLE (-3300 4650);
FORCEPROP 1 LAST NEEDS_NO_SIZE TRUE
J 0
(-3300 4650);
DISPLAY 0.468085 (-3300 4650);
PAINT GREEN (-3300 4650);
DISPLAY INVISIBLE (-3300 4650);
FORCEPROP 1 LAST PATH I35
J 0
(-3225 4705);
DISPLAY 0.723404 (-3225 4705);
PAINT GREEN (-3225 4705);
DISPLAY INVISIBLE (-3225 4705);
FORCEPROP 0 LAST CDS_LOCATION L18
J 0
(-3425 4950);
DISPLAY 1.021277 (-3425 4950);
DISPLAY INVISIBLE (-3425 4950);
FORCEPROP 0 LAST $SEC 1
J 0
(-3425 4950);
DISPLAY 0.680851 (-3425 4950);
PAINT MONO (-3425 4950);
DISPLAY INVISIBLE (-3425 4950);
FORCEPROP 0 LAST CDS_SEC 1
J 0
(-3425 4950);
DISPLAY 1.021277 (-3425 4950);
DISPLAY INVISIBLE (-3425 4950);
FORCEADD UNIVERSAL_GND..1
(-3025 4025);
FORCEPROP 3 LASTPIN (-3025 4075) SIG_NAME GND\g
J 0
(-3015 4085);
DISPLAY 0.659574 (-3015 4085);
PAINT MONO (-3015 4085);
DISPLAY INVISIBLE (-3015 4085);
FORCEPROP 2 LAST CDS_LIB logical_power
J 0
(-3025 4025);
DISPLAY INVISIBLE (-3025 4025);
FORCEPROP 1 LAST HDL_POWER GND
J 1
(-3000 3950);
DISPLAY 0.872340 (-3000 3950);
PAINT GREEN (-3000 3950);
DISPLAY INVISIBLE (-3000 3950);
FORCEPROP 1 LAST PATH I36
J 0
(-2950 4025);
DISPLAY 0.872340 (-2950 4025);
PAINT AQUA (-2950 4025);
DISPLAY INVISIBLE (-2950 4025);
FORCEADD Q_CAP..1
(-3025 4375);
FORCEPROP 1 LAST PART_NUMBER CH6223MEA00
J 0
(-2975 4225);
DISPLAY 0.638298 (-2975 4225);
DISPLAY INVISIBLE (-2975 4225);
FORCEPROP 1 LAST MATERIAL X6S
J 0
(-2975 4275);
DISPLAY 0.638298 (-2975 4275);
FORCEPROP 1 LAST VOLTAGE 16V
J 0
(-2975 4375);
DISPLAY 0.638298 (-2975 4375);
FORCEPROP 1 LAST VALUE 22UF
J 0
(-2975 4425);
DISPLAY 0.638298 (-2975 4425);
FORCEPROP 1 LAST PACK_TYPE C0805
J 0
(-2975 4175);
DISPLAY 0.638298 (-2975 4175);
FORCEPROP 1 LAST TOLERANCE 20%
J 0
(-2975 4325);
DISPLAY 0.638298 (-2975 4325);
FORCEPROP 1 LAST LOCATION C2284
J 0
(-2975 4475);
DISPLAY 0.787234 (-2975 4475);
FORCEPROP 1 LASTPIN (-3025 4475) $PN 1
J 0
(-3015 4455);
DISPLAY 0.787234 (-3015 4455);
PAINT MONO (-3015 4455);
FORCEPROP 1 LASTPIN (-3025 4275) $PN 2
J 0
(-3015 4255);
DISPLAY 0.787234 (-3015 4255);
PAINT MONO (-3015 4255);
FORCEPROP 2 LAST CDS_LIB pure_quanta
J 0
(-3025 4375);
DISPLAY INVISIBLE (-3025 4375);
FORCEPROP 1 LAST PATH I37
J 0
(-2975 4525);
DISPLAY 0.978723 (-2975 4525);
PAINT WHITE (-2975 4525);
DISPLAY INVISIBLE (-2975 4525);
FORCEPROP 0 LAST $SEC 1
J 0
(-2975 4525);
DISPLAY 0.680851 (-2975 4525);
PAINT MONO (-2975 4525);
DISPLAY INVISIBLE (-2975 4525);
FORCEPROP 0 LAST CDS_SEC 1
J 0
(-2975 4525);
DISPLAY 1.021277 (-2975 4525);
DISPLAY INVISIBLE (-2975 4525);
FORCEADD UNIVERSAL_POWER..1
(-3650 4800);
FORCEPROP 3 LASTPIN (-3650 4750) SIG_NAME P3V3_AUX\g
J 0
(-3640 4760);
DISPLAY 0.659574 (-3640 4760);
PAINT MONO (-3640 4760);
DISPLAY INVISIBLE (-3640 4760);
FORCEPROP 1 LAST HDL_POWER P3V3_AUX
J 1
(-3650 4850);
DISPLAY 0.872340 (-3650 4850);
PAINT GREEN (-3650 4850);
FORCEPROP 2 LAST CDS_LIB logical_power
J 0
(-3650 4800);
DISPLAY INVISIBLE (-3650 4800);
FORCEPROP 1 LAST PATH I38
J 0
(-3600 4825);
DISPLAY 0.872340 (-3600 4825);
PAINT AQUA (-3600 4825);
DISPLAY INVISIBLE (-3600 4825);
FORCEADD UNIVERSAL_GND..1
(-750 725);
FORCEPROP 3 LASTPIN (-750 775) SIG_NAME GND\g
J 0
(-740 785);
DISPLAY 0.659574 (-740 785);
PAINT MONO (-740 785);
DISPLAY INVISIBLE (-740 785);
FORCEPROP 2 LAST CDS_LIB logical_power
J 0
(-750 725);
DISPLAY INVISIBLE (-750 725);
FORCEPROP 1 LAST HDL_POWER GND
J 1
(-725 650);
DISPLAY 0.872340 (-725 650);
PAINT GREEN (-725 650);
DISPLAY INVISIBLE (-725 650);
FORCEPROP 2 LAST ROOM IO_SLOT
J 1
(-975 800);
DISPLAY 0.744681 (-975 800);
DISPLAY INVISIBLE (-975 800);
FORCEPROP 1 LAST PATH I39
J 0
(-675 725);
DISPLAY 0.872340 (-675 725);
PAINT AQUA (-675 725);
DISPLAY INVISIBLE (-675 725);
FORCEADD UNIVERSAL_POWER..1
(-5025 175);
FORCEPROP 3 LASTPIN (-5025 125) SIG_NAME P3V3_AUX\g
J 0
(-5015 135);
DISPLAY 0.659574 (-5015 135);
PAINT MONO (-5015 135);
DISPLAY INVISIBLE (-5015 135);
FORCEPROP 1 LAST HDL_POWER P3V3_AUX
J 1
(-5025 225);
DISPLAY 0.872340 (-5025 225);
PAINT GREEN (-5025 225);
FORCEPROP 2 LAST CDS_LIB logical_power
J 0
(-5025 175);
DISPLAY INVISIBLE (-5025 175);
FORCEPROP 1 LAST PATH I4
J 0
(-4975 200);
DISPLAY 0.872340 (-4975 200);
PAINT AQUA (-4975 200);
DISPLAY INVISIBLE (-4975 200);
FORCEADD Q_RES..2
(-750 1075);
FORCEPROP 1 LAST PART_NUMBER CS21002FB06
J 0
(-710 950);
DISPLAY 0.638298 (-710 950);
DISPLAY INVISIBLE (-710 950);
FORCEPROP 1 LAST VALUE 1K
J 0
(-705 1150);
DISPLAY 0.638298 (-705 1150);
FORCEPROP 1 LAST PACK_TYPE 0402LF
J 0
(-710 900);
DISPLAY 0.638298 (-710 900);
FORCEPROP 1 LAST MATERIAL EMPTY
J 0
(-710 1000);
DISPLAY 0.638298 (-710 1000);
PAINT RED (-710 1000);
FORCEPROP 1 LAST TOLERANCE 1%
J 0
(-705 1100);
DISPLAY 0.638298 (-705 1100);
FORCEPROP 1 LAST WATTAGE 1/16W
J 0
(-710 1050);
DISPLAY 0.638298 (-710 1050);
FORCEPROP 1 LAST $LOCATION R4285
J 0
(-705 1200);
DISPLAY 0.978723 (-705 1200);
FORCEPROP 1 LASTPIN (-750 1175) $PN 1
J 0
(-745 1137);
DISPLAY 0.787234 (-745 1137);
PAINT MONO (-745 1137);
FORCEPROP 1 LASTPIN (-750 975) $PN 2
J 0
(-745 985);
DISPLAY 0.787234 (-745 985);
PAINT MONO (-745 985);
FORCEPROP 2 LAST CDS_LIB pure_quanta
J 0
(-750 1075);
DISPLAY INVISIBLE (-750 1075);
FORCEPROP 1 LAST PATH I40
J 0
(-700 1250);
DISPLAY 0.978723 (-700 1250);
PAINT WHITE (-700 1250);
DISPLAY INVISIBLE (-700 1250);
FORCEPROP 0 LAST CDS_LOCATION R4285
J 0
(-700 1250);
DISPLAY 1.021277 (-700 1250);
DISPLAY INVISIBLE (-700 1250);
FORCEPROP 0 LAST $SEC 1
J 0
(-700 1250);
DISPLAY 0.680851 (-700 1250);
PAINT MONO (-700 1250);
DISPLAY INVISIBLE (-700 1250);
FORCEPROP 0 LAST CDS_SEC 1
J 0
(-700 1250);
DISPLAY 1.021277 (-700 1250);
DISPLAY INVISIBLE (-700 1250);
FORCEADD Q_RES..2
(-750 1600);
FORCEPROP 1 LAST PART_NUMBER CS21002FB06
J 0
(-710 1475);
DISPLAY 0.638298 (-710 1475);
DISPLAY INVISIBLE (-710 1475);
FORCEPROP 1 LAST PACK_TYPE 0402LF
J 0
(-710 1425);
DISPLAY 0.638298 (-710 1425);
FORCEPROP 1 LAST MATERIAL EMPTY
J 0
(-710 1525);
DISPLAY 0.638298 (-710 1525);
PAINT RED (-710 1525);
FORCEPROP 1 LAST VALUE 1K
J 0
(-705 1675);
DISPLAY 0.638298 (-705 1675);
FORCEPROP 1 LAST WATTAGE 1/16W
J 0
(-710 1575);
DISPLAY 0.638298 (-710 1575);
FORCEPROP 1 LAST TOLERANCE 1%
J 0
(-705 1625);
DISPLAY 0.638298 (-705 1625);
FORCEPROP 1 LAST $LOCATION R4284
J 0
(-705 1725);
DISPLAY 0.638298 (-705 1725);
FORCEPROP 1 LASTPIN (-750 1700) $PN 1
J 0
(-745 1662);
DISPLAY 0.787234 (-745 1662);
PAINT MONO (-745 1662);
FORCEPROP 1 LASTPIN (-750 1500) $PN 2
J 0
(-745 1510);
DISPLAY 0.787234 (-745 1510);
PAINT MONO (-745 1510);
FORCEPROP 2 LAST CDS_LIB pure_quanta
J 0
(-750 1600);
DISPLAY INVISIBLE (-750 1600);
FORCEPROP 1 LAST PATH I41
J 0
(-700 1775);
DISPLAY 0.978723 (-700 1775);
PAINT WHITE (-700 1775);
DISPLAY INVISIBLE (-700 1775);
FORCEPROP 0 LAST CDS_LOCATION R4284
J 0
(-700 1775);
DISPLAY 1.021277 (-700 1775);
DISPLAY INVISIBLE (-700 1775);
FORCEPROP 0 LAST $SEC 1
J 0
(-700 1775);
DISPLAY 0.680851 (-700 1775);
PAINT MONO (-700 1775);
DISPLAY INVISIBLE (-700 1775);
FORCEPROP 0 LAST CDS_SEC 1
J 0
(-700 1775);
DISPLAY 1.021277 (-700 1775);
DISPLAY INVISIBLE (-700 1775);
FORCEADD UNIVERSAL_POWER..1
(-750 1900);
FORCEPROP 3 LASTPIN (-750 1850) SIG_NAME P3V3_AUX\g
J 0
(-740 1860);
DISPLAY 0.659574 (-740 1860);
PAINT MONO (-740 1860);
DISPLAY INVISIBLE (-740 1860);
FORCEPROP 1 LAST HDL_POWER P3V3_AUX
J 1
(-750 1950);
DISPLAY 0.872340 (-750 1950);
PAINT GREEN (-750 1950);
FORCEPROP 2 LAST CDS_LIB logical_power
J 0
(-750 1900);
DISPLAY INVISIBLE (-750 1900);
FORCEPROP 1 LAST PATH I42
J 0
(-700 1925);
DISPLAY 0.872340 (-700 1925);
PAINT AQUA (-700 1925);
DISPLAY INVISIBLE (-700 1925);
FORCEADD PI3EQX1002EZREX..1
(-1550 3550);
FORCEPROP 1 LAST PART_NUMBER AL001002007
J 0
(-1843 4310);
DISPLAY 0.723404 (-1843 4310);
PAINT GREEN (-1843 4310);
DISPLAY INVISIBLE (-1843 4310);
FORCEPROP 1 LAST MATERIAL IC
J 0
(-1843 4183);
DISPLAY 0.723404 (-1843 4183);
PAINT GREEN (-1843 4183);
FORCEPROP 2 LAST PART_TYPE SMLF
J 0
(-1825 4550);
DISPLAY 1.021277 (-1825 4550);
FORCEPROP 2 LAST VALUE PI3EQX1002EZREX
J 0
(-1825 4500);
DISPLAY 1.021277 (-1825 4500);
FORCEPROP 1 LAST LOCATION U309
J 0
(-1843 4457);
DISPLAY 0.723404 (-1843 4457);
PAINT GREEN (-1843 4457);
FORCEPROP 0 LASTPIN (-2000 3325) $PN 7
J 2
(-2010 3335);
DISPLAY 0.680851 (-2010 3335);
PAINT MONO (-2010 3335);
FORCEPROP 0 LASTPIN (-2000 3375) $PN 6
J 2
(-2010 3385);
DISPLAY 0.680851 (-2010 3385);
PAINT MONO (-2010 3385);
FORCEPROP 0 LASTPIN (-1100 4025) $PN 23
J 0
(-1090 4035);
DISPLAY 0.680851 (-1090 4035);
PAINT MONO (-1090 4035);
FORCEPROP 0 LASTPIN (-1100 4075) $PN 24
J 0
(-1090 4085);
DISPLAY 0.680851 (-1090 4085);
PAINT MONO (-1090 4085);
FORCEPROP 0 LASTPIN (-2000 3175) $PN 19
J 2
(-2010 3185);
DISPLAY 0.680851 (-2010 3185);
PAINT MONO (-2010 3185);
FORCEPROP 0 LASTPIN (-2000 3225) $PN 18
J 2
(-2010 3235);
DISPLAY 0.680851 (-2010 3235);
PAINT MONO (-2010 3235);
FORCEPROP 0 LASTPIN (-1100 3825) $PN 11
J 0
(-1090 3835);
DISPLAY 0.680851 (-1090 3835);
PAINT MONO (-1090 3835);
FORCEPROP 0 LASTPIN (-1100 3875) $PN 12
J 0
(-1090 3885);
DISPLAY 0.680851 (-1090 3885);
PAINT MONO (-1090 3885);
FORCEPROP 0 LASTPIN (-1100 3575) $PN 4
J 0
(-1090 3585);
DISPLAY 0.680851 (-1090 3585);
PAINT MONO (-1090 3585);
FORCEPROP 0 LASTPIN (-2000 3575) $PN 1
J 2
(-2010 3585);
DISPLAY 0.680851 (-2010 3585);
PAINT MONO (-2010 3585);
FORCEPROP 0 LASTPIN (-2000 3525) $PN 16
J 2
(-2010 3535);
DISPLAY 0.680851 (-2010 3535);
PAINT MONO (-2010 3535);
FORCEPROP 0 LASTPIN (-2000 3875) $PN 2
J 2
(-2010 3885);
DISPLAY 0.680851 (-2010 3885);
PAINT MONO (-2010 3885);
FORCEPROP 0 LASTPIN (-2000 3825) $PN 15
J 2
(-2010 3835);
DISPLAY 0.680851 (-2010 3835);
PAINT MONO (-2010 3835);
FORCEPROP 0 LASTPIN (-1100 3425) $PN 8
J 0
(-1090 3435);
DISPLAY 0.680851 (-1090 3435);
PAINT MONO (-1090 3435);
FORCEPROP 0 LASTPIN (-1100 3375) $PN 9
J 0
(-1090 3385);
DISPLAY 0.680851 (-1090 3385);
PAINT MONO (-1090 3385);
FORCEPROP 0 LASTPIN (-1100 3325) $PN 10
J 0
(-1090 3335);
DISPLAY 0.680851 (-1090 3335);
PAINT MONO (-1090 3335);
FORCEPROP 0 LASTPIN (-1100 3275) $PN 20
J 0
(-1090 3285);
DISPLAY 0.680851 (-1090 3285);
PAINT MONO (-1090 3285);
FORCEPROP 0 LASTPIN (-1100 3225) $PN 21
J 0
(-1090 3235);
DISPLAY 0.680851 (-1090 3235);
PAINT MONO (-1090 3235);
FORCEPROP 0 LASTPIN (-1100 3175) $PN 22
J 0
(-1090 3185);
DISPLAY 0.680851 (-1090 3185);
PAINT MONO (-1090 3185);
FORCEPROP 0 LASTPIN (-1100 3725) $PN 13
J 0
(-1090 3735);
DISPLAY 0.680851 (-1090 3735);
PAINT MONO (-1090 3735);
FORCEPROP 0 LASTPIN (-2000 3725) $PN 3
J 2
(-2010 3735);
DISPLAY 0.680851 (-2010 3735);
PAINT MONO (-2010 3735);
FORCEPROP 0 LASTPIN (-2000 3675) $PN 14
J 2
(-2010 3685);
DISPLAY 0.680851 (-2010 3685);
PAINT MONO (-2010 3685);
FORCEPROP 0 LASTPIN (-1100 3025) $PN TH
J 0
(-1090 3035);
DISPLAY 0.680851 (-1090 3035);
PAINT MONO (-1090 3035);
FORCEPROP 0 LASTPIN (-2000 4075) $PN 5
J 2
(-2010 4085);
DISPLAY 0.680851 (-2010 4085);
PAINT MONO (-2010 4085);
FORCEPROP 0 LASTPIN (-2000 4025) $PN 17
J 2
(-2010 4035);
DISPLAY 0.680851 (-2010 4035);
PAINT MONO (-2010 4035);
FORCEPROP 1 LAST CDS_LMAN_SYM_OUTLINE -300,625,300,-625
J 0
(-1550 3550);
DISPLAY 0.468085 (-1550 3550);
PAINT GREEN (-1550 3550);
DISPLAY INVISIBLE (-1550 3550);
FORCEPROP 1 LAST NEEDS_NO_SIZE TRUE
J 0
(-1550 3550);
DISPLAY 0.723404 (-1550 3550);
PAINT GREEN (-1550 3550);
DISPLAY INVISIBLE (-1550 3550);
FORCEPROP 2 LAST CDS_LIB pure_quanta
J 0
(-1550 3550);
DISPLAY INVISIBLE (-1550 3550);
FORCEPROP 1 LAST PATH I43
J 0
(-1550 3550);
DISPLAY 0.723404 (-1550 3550);
PAINT GREEN (-1550 3550);
DISPLAY INVISIBLE (-1550 3550);
FORCEPROP 0 LAST $SEC 1
J 0
(-1825 4600);
DISPLAY 0.680851 (-1825 4600);
PAINT MONO (-1825 4600);
DISPLAY INVISIBLE (-1825 4600);
FORCEPROP 0 LAST CDS_SEC 1
J 0
(-1825 4600);
DISPLAY 1.021277 (-1825 4600);
DISPLAY INVISIBLE (-1825 4600);
FORCEADD Q_CAP..1
(-2650 4375);
FORCEPROP 1 LAST PART_NUMBER CH4104K1B00
J 0
(-2600 4225);
DISPLAY 0.808511 (-2600 4225);
DISPLAY INVISIBLE (-2600 4225);
FORCEPROP 1 LAST PACK_TYPE 0402
J 0
(-2600 4225);
DISPLAY 0.638298 (-2600 4225);
FORCEPROP 1 LAST TOLERANCE 10%
J 0
(-2600 4325);
DISPLAY 0.638298 (-2600 4325);
FORCEPROP 1 LAST MATERIAL X7R
J 0
(-2600 4275);
DISPLAY 0.638298 (-2600 4275);
FORCEPROP 1 LAST VOLTAGE 25V
J 0
(-2600 4375);
DISPLAY 0.638298 (-2600 4375);
FORCEPROP 1 LAST VALUE 0.1UF
J 0
(-2600 4425);
DISPLAY 0.638298 (-2600 4425);
FORCEPROP 1 LAST $LOCATION C2285
J 0
(-2600 4475);
DISPLAY 0.787234 (-2600 4475);
FORCEPROP 1 LASTPIN (-2650 4475) $PN 1
J 0
(-2640 4455);
DISPLAY 0.787234 (-2640 4455);
FORCEPROP 1 LASTPIN (-2650 4275) $PN 2
J 0
(-2640 4255);
DISPLAY 0.787234 (-2640 4255);
FORCEPROP 2 LAST CDS_LIB pure_quanta
J 0
(-2650 4375);
PAINT MONO (-2650 4375);
DISPLAY INVISIBLE (-2650 4375);
FORCEPROP 1 LAST PATH I44
J 0
(-2600 4525);
DISPLAY 0.978723 (-2600 4525);
PAINT WHITE (-2600 4525);
DISPLAY INVISIBLE (-2600 4525);
FORCEPROP 2 LAST CDS_LOCATION C2285
J 0
(-2600 4575);
DISPLAY 1.021277 (-2600 4575);
DISPLAY INVISIBLE (-2600 4575);
FORCEPROP 2 LAST $SEC 1
J 0
(-2600 4575);
DISPLAY 0.680851 (-2600 4575);
PAINT MONO (-2600 4575);
DISPLAY INVISIBLE (-2600 4575);
FORCEPROP 2 LAST CDS_SEC 1
J 0
(-2600 4575);
DISPLAY 1.021277 (-2600 4575);
DISPLAY INVISIBLE (-2600 4575);
FORCEADD Q_CAP..1
(-2375 4375);
FORCEPROP 1 LAST PART_NUMBER CH4104K1B00
J 0
(-2325 4225);
DISPLAY 0.808511 (-2325 4225);
DISPLAY INVISIBLE (-2325 4225);
FORCEPROP 1 LAST TOLERANCE 10%
J 0
(-2325 4325);
DISPLAY 0.638298 (-2325 4325);
FORCEPROP 1 LAST VOLTAGE 25V
J 0
(-2325 4375);
DISPLAY 0.638298 (-2325 4375);
FORCEPROP 1 LAST VALUE 0.1UF
J 0
(-2325 4425);
DISPLAY 0.638298 (-2325 4425);
FORCEPROP 1 LAST MATERIAL X7R
J 0
(-2325 4275);
DISPLAY 0.638298 (-2325 4275);
FORCEPROP 1 LAST PACK_TYPE 0402
J 0
(-2325 4225);
DISPLAY 0.638298 (-2325 4225);
FORCEPROP 1 LAST $LOCATION C2286
J 0
(-2325 4475);
DISPLAY 0.787234 (-2325 4475);
FORCEPROP 1 LASTPIN (-2375 4475) $PN 1
J 0
(-2365 4455);
DISPLAY 0.787234 (-2365 4455);
FORCEPROP 1 LASTPIN (-2375 4275) $PN 2
J 0
(-2365 4255);
DISPLAY 0.787234 (-2365 4255);
FORCEPROP 2 LAST CDS_LIB pure_quanta
J 0
(-2375 4375);
PAINT MONO (-2375 4375);
DISPLAY INVISIBLE (-2375 4375);
FORCEPROP 1 LAST PATH I45
J 0
(-2325 4525);
DISPLAY 0.978723 (-2325 4525);
PAINT WHITE (-2325 4525);
DISPLAY INVISIBLE (-2325 4525);
FORCEPROP 2 LAST CDS_LOCATION C2286
J 0
(-2325 4575);
DISPLAY 1.021277 (-2325 4575);
DISPLAY INVISIBLE (-2325 4575);
FORCEPROP 2 LAST $SEC 1
J 0
(-2325 4575);
DISPLAY 0.680851 (-2325 4575);
PAINT MONO (-2325 4575);
DISPLAY INVISIBLE (-2325 4575);
FORCEPROP 2 LAST CDS_SEC 1
J 0
(-2325 4575);
DISPLAY 1.021277 (-2325 4575);
DISPLAY INVISIBLE (-2325 4575);
FORCEADD UNIVERSAL_GND..1
(-1025 2775);
FORCEPROP 3 LASTPIN (-1025 2825) SIG_NAME GND\g
J 0
(-1015 2835);
DISPLAY 0.659574 (-1015 2835);
PAINT MONO (-1015 2835);
DISPLAY INVISIBLE (-1015 2835);
FORCEPROP 2 LAST CDS_LIB logical_power
J 0
(-1025 2775);
DISPLAY INVISIBLE (-1025 2775);
FORCEPROP 1 LAST HDL_POWER GND
J 1
(-1000 2700);
DISPLAY 0.872340 (-1000 2700);
PAINT GREEN (-1000 2700);
DISPLAY INVISIBLE (-1000 2700);
FORCEPROP 1 LAST PATH I46
J 0
(-950 2775);
DISPLAY 0.872340 (-950 2775);
PAINT AQUA (-950 2775);
DISPLAY INVISIBLE (-950 2775);
FORCEADD UNIVERSAL_GND..1
(125 725);
FORCEPROP 3 LASTPIN (125 775) SIG_NAME GND\g
J 0
(135 785);
DISPLAY 0.659574 (135 785);
PAINT MONO (135 785);
DISPLAY INVISIBLE (135 785);
FORCEPROP 2 LAST CDS_LIB logical_power
J 0
(125 725);
DISPLAY INVISIBLE (125 725);
FORCEPROP 1 LAST HDL_POWER GND
J 1
(150 650);
DISPLAY 0.872340 (150 650);
PAINT GREEN (150 650);
DISPLAY INVISIBLE (150 650);
FORCEPROP 2 LAST ROOM IO_SLOT
J 1
(-100 800);
DISPLAY 0.744681 (-100 800);
DISPLAY INVISIBLE (-100 800);
FORCEPROP 1 LAST PATH I47
J 0
(200 725);
DISPLAY 0.872340 (200 725);
PAINT AQUA (200 725);
DISPLAY INVISIBLE (200 725);
FORCEADD Q_RES..2
(125 1025);
FORCEPROP 1 LAST PART_NUMBER CS21002FB06
J 0
(165 900);
DISPLAY 0.638298 (165 900);
DISPLAY INVISIBLE (165 900);
FORCEPROP 1 LAST TOLERANCE 1%
J 0
(170 1050);
DISPLAY 0.638298 (170 1050);
FORCEPROP 1 LAST VALUE 1K
J 0
(170 1100);
DISPLAY 0.638298 (170 1100);
FORCEPROP 1 LAST WATTAGE 1/16W
J 0
(165 1000);
DISPLAY 0.638298 (165 1000);
FORCEPROP 1 LAST MATERIAL EMPTY
J 0
(165 950);
DISPLAY 0.638298 (165 950);
PAINT RED (165 950);
FORCEPROP 1 LAST PACK_TYPE 0402LF
J 0
(165 850);
DISPLAY 0.638298 (165 850);
FORCEPROP 1 LAST $LOCATION R4288
J 0
(170 1150);
DISPLAY 0.978723 (170 1150);
FORCEPROP 1 LASTPIN (125 1125) $PN 1
J 0
(130 1087);
DISPLAY 0.787234 (130 1087);
PAINT MONO (130 1087);
FORCEPROP 1 LASTPIN (125 925) $PN 2
J 0
(130 935);
DISPLAY 0.787234 (130 935);
PAINT MONO (130 935);
FORCEPROP 2 LAST CDS_LIB pure_quanta
J 0
(125 1025);
DISPLAY INVISIBLE (125 1025);
FORCEPROP 1 LAST PATH I48
J 0
(175 1200);
DISPLAY 0.978723 (175 1200);
PAINT WHITE (175 1200);
DISPLAY INVISIBLE (175 1200);
FORCEPROP 0 LAST CDS_LOCATION R4288
J 0
(175 1200);
DISPLAY 1.021277 (175 1200);
DISPLAY INVISIBLE (175 1200);
FORCEPROP 0 LAST $SEC 1
J 0
(175 1200);
DISPLAY 0.680851 (175 1200);
PAINT MONO (175 1200);
DISPLAY INVISIBLE (175 1200);
FORCEPROP 0 LAST CDS_SEC 1
J 0
(175 1200);
DISPLAY 1.021277 (175 1200);
DISPLAY INVISIBLE (175 1200);
FORCEADD Q_RES..2
(125 1600);
FORCEPROP 1 LAST PART_NUMBER CS21002FB06
J 0
(165 1475);
DISPLAY 0.638298 (165 1475);
DISPLAY INVISIBLE (165 1475);
FORCEPROP 1 LAST WATTAGE 1/16W
J 0
(165 1575);
DISPLAY 0.638298 (165 1575);
FORCEPROP 1 LAST VALUE 1K
J 0
(170 1675);
DISPLAY 0.638298 (170 1675);
FORCEPROP 1 LAST TOLERANCE 1%
J 0
(170 1625);
DISPLAY 0.638298 (170 1625);
FORCEPROP 1 LAST MATERIAL EMPTY
J 0
(165 1525);
DISPLAY 0.638298 (165 1525);
PAINT RED (165 1525);
FORCEPROP 1 LAST PACK_TYPE 0402LF
J 0
(165 1425);
DISPLAY 0.638298 (165 1425);
FORCEPROP 1 LAST $LOCATION R4287
J 0
(170 1725);
DISPLAY 0.978723 (170 1725);
FORCEPROP 1 LASTPIN (125 1700) $PN 1
J 0
(130 1662);
DISPLAY 0.787234 (130 1662);
PAINT MONO (130 1662);
FORCEPROP 1 LASTPIN (125 1500) $PN 2
J 0
(130 1510);
DISPLAY 0.787234 (130 1510);
PAINT MONO (130 1510);
FORCEPROP 2 LAST CDS_LIB pure_quanta
J 0
(125 1600);
DISPLAY INVISIBLE (125 1600);
FORCEPROP 1 LAST PATH I49
J 0
(175 1775);
DISPLAY 0.978723 (175 1775);
PAINT WHITE (175 1775);
DISPLAY INVISIBLE (175 1775);
FORCEPROP 0 LAST CDS_LOCATION R4287
J 0
(175 1775);
DISPLAY 1.021277 (175 1775);
DISPLAY INVISIBLE (175 1775);
FORCEPROP 0 LAST $SEC 1
J 0
(175 1775);
DISPLAY 0.680851 (175 1775);
PAINT MONO (175 1775);
DISPLAY INVISIBLE (175 1775);
FORCEPROP 0 LAST CDS_SEC 1
J 0
(175 1775);
DISPLAY 1.021277 (175 1775);
DISPLAY INVISIBLE (175 1775);
FORCEADD UNIVERSAL_GND..1
(-4150 -1000);
FORCEPROP 3 LASTPIN (-4150 -950) SIG_NAME GND\g
J 0
(-4140 -940);
DISPLAY 0.659574 (-4140 -940);
PAINT MONO (-4140 -940);
DISPLAY INVISIBLE (-4140 -940);
FORCEPROP 2 LAST CDS_LIB logical_power
J 0
(-4150 -1000);
DISPLAY INVISIBLE (-4150 -1000);
FORCEPROP 1 LAST HDL_POWER GND
J 1
(-4125 -1075);
DISPLAY 0.872340 (-4125 -1075);
PAINT GREEN (-4125 -1075);
DISPLAY INVISIBLE (-4125 -1075);
FORCEPROP 2 LAST ROOM IO_SLOT
J 1
(-4375 -925);
DISPLAY 0.744681 (-4375 -925);
DISPLAY INVISIBLE (-4375 -925);
FORCEPROP 1 LAST PATH I5
J 0
(-4075 -1000);
DISPLAY 0.872340 (-4075 -1000);
PAINT AQUA (-4075 -1000);
DISPLAY INVISIBLE (-4075 -1000);
FORCEADD OFFPAGE..2
(625 1350);
FORCEPROP 2 LAST $XR0 169 
J 0
(814 1350);
DISPLAY 0.638298 (814 1350);
PAINT MONO (814 1350);
FORCEPROP 2 LAST CDS_LIB standard
J 0
(625 1350);
DISPLAY INVISIBLE (625 1350);
FORCEPROP 1 LAST OFFPAGE TRUE
J 0
(950 1225);
DISPLAY 0.872340 (950 1225);
PAINT GREEN (950 1225);
DISPLAY INVISIBLE (950 1225);
FORCEPROP 1 LAST COMMENT_BODY TRUE
J 0
(580 1255);
DISPLAY 0.872340 (580 1255);
PAINT GREEN (580 1255);
DISPLAY INVISIBLE (580 1255);
FORCEPROP 2 LAST PATH I50
J 0
(825 1400);
DISPLAY 1.021277 (825 1400);
DISPLAY INVISIBLE (825 1400);
FORCEADD OFFPAGE..2
(625 1300);
FORCEPROP 2 LAST $XR0 169 
J 0
(814 1300);
DISPLAY 0.638298 (814 1300);
PAINT MONO (814 1300);
FORCEPROP 2 LAST CDS_LIB standard
J 0
(625 1300);
DISPLAY INVISIBLE (625 1300);
FORCEPROP 1 LAST OFFPAGE TRUE
J 0
(950 1175);
DISPLAY 0.872340 (950 1175);
PAINT GREEN (950 1175);
DISPLAY INVISIBLE (950 1175);
FORCEPROP 1 LAST COMMENT_BODY TRUE
J 0
(580 1205);
DISPLAY 0.872340 (580 1205);
PAINT GREEN (580 1205);
DISPLAY INVISIBLE (580 1205);
FORCEPROP 2 LAST PATH I51
J 0
(825 1350);
DISPLAY 1.021277 (825 1350);
DISPLAY INVISIBLE (825 1350);
FORCEADD OFFPAGE..4
(-175 3575);
FORCEPROP 2 LAST $XR0 169 
J 0
(11 3575);
DISPLAY 0.638298 (11 3575);
PAINT MONO (11 3575);
FORCEPROP 2 LAST CDS_LIB standard
J 0
(-175 3575);
DISPLAY INVISIBLE (-175 3575);
FORCEPROP 1 LAST OFFPAGE TRUE
J 0
(150 3450);
DISPLAY 0.872340 (150 3450);
PAINT GREEN (150 3450);
DISPLAY INVISIBLE (150 3450);
FORCEPROP 1 LAST COMMENT_BODY TRUE
J 0
(-200 3475);
DISPLAY 0.872340 (-200 3475);
PAINT GREEN (-200 3475);
DISPLAY INVISIBLE (-200 3475);
FORCEPROP 2 LAST PATH I52
J 0
(25 3625);
DISPLAY 1.021277 (25 3625);
DISPLAY INVISIBLE (25 3625);
FORCEADD OFFPAGE..4
(-175 3725);
FORCEPROP 2 LAST $XR0 169 
J 0
(11 3725);
DISPLAY 0.638298 (11 3725);
PAINT MONO (11 3725);
FORCEPROP 2 LAST CDS_LIB standard
J 0
(-175 3725);
DISPLAY INVISIBLE (-175 3725);
FORCEPROP 1 LAST OFFPAGE TRUE
J 0
(150 3600);
DISPLAY 0.872340 (150 3600);
PAINT GREEN (150 3600);
DISPLAY INVISIBLE (150 3600);
FORCEPROP 1 LAST COMMENT_BODY TRUE
J 0
(-200 3625);
DISPLAY 0.872340 (-200 3625);
PAINT GREEN (-200 3625);
DISPLAY INVISIBLE (-200 3625);
FORCEPROP 2 LAST PATH I53
J 0
(25 3775);
DISPLAY 1.021277 (25 3775);
DISPLAY INVISIBLE (25 3775);
FORCEADD Q_CAP..2
(0 3825);
FORCEPROP 1 LAST PART_NUMBER CH4101KEE01
J 1
(0 3875);
DISPLAY 0.978723 (0 3875);
DISPLAY INVISIBLE (0 3875);
FORCEPROP 1 LAST MATERIAL X6S
J 0
(75 3825);
DISPLAY 0.638298 (75 3825);
FORCEPROP 1 LAST VALUE 0.1UF
J 2
(-150 3825);
DISPLAY 0.638298 (-150 3825);
FORCEPROP 1 LAST $LOCATION C2292
J 1
(225 3825);
DISPLAY 0.638298 (225 3825);
FORCEPROP 1 LASTPIN (-100 3825) $PN 1
J 0
(-110 3840);
DISPLAY 0.787234 (-110 3840);
PAINT MONO (-110 3840);
FORCEPROP 1 LASTPIN (100 3825) $PN 2
J 0
(85 3840);
DISPLAY 0.787234 (85 3840);
PAINT MONO (85 3840);
FORCEPROP 2 LAST CDS_LIB pure_quanta
J 0
(0 3825);
DISPLAY INVISIBLE (0 3825);
FORCEPROP 1 LAST PACK_TYPE C0201
J 1
(0 3625);
DISPLAY 0.978723 (0 3625);
DISPLAY INVISIBLE (0 3625);
FORCEPROP 1 LAST TOLERANCE 10%
J 2
(0 3675);
DISPLAY 0.978723 (0 3675);
DISPLAY INVISIBLE (0 3675);
FORCEPROP 1 LAST VOLTAGE 6.3V
J 0
(0 3725);
DISPLAY 0.978723 (0 3725);
DISPLAY INVISIBLE (0 3725);
FORCEPROP 1 LAST PATH I54
J 0
(0 4025);
DISPLAY 0.978723 (0 4025);
PAINT WHITE (0 4025);
DISPLAY INVISIBLE (0 4025);
FORCEPROP 0 LAST CDS_LOCATION C2292
J 0
(-125 3875);
DISPLAY 1.021277 (-125 3875);
DISPLAY INVISIBLE (-125 3875);
FORCEPROP 0 LAST $SEC 1
J 0
(225 3875);
DISPLAY 0.680851 (225 3875);
PAINT MONO (225 3875);
DISPLAY INVISIBLE (225 3875);
FORCEPROP 0 LAST CDS_SEC 1
J 0
(-125 3875);
DISPLAY 1.021277 (-125 3875);
DISPLAY INVISIBLE (-125 3875);
FORCEADD Q_CAP..2
(0 3875);
FORCEPROP 1 LAST PART_NUMBER CH4101KEE01
J 1
(0 3925);
DISPLAY 0.978723 (0 3925);
DISPLAY INVISIBLE (0 3925);
FORCEPROP 1 LAST MATERIAL X6S
J 0
(75 3875);
DISPLAY 0.638298 (75 3875);
FORCEPROP 1 LAST VALUE 0.1UF
J 2
(-150 3875);
DISPLAY 0.638298 (-150 3875);
FORCEPROP 1 LAST $LOCATION C2291
J 1
(225 3875);
DISPLAY 0.638298 (225 3875);
FORCEPROP 1 LASTPIN (-100 3875) $PN 1
J 0
(-110 3890);
DISPLAY 0.787234 (-110 3890);
PAINT MONO (-110 3890);
FORCEPROP 1 LASTPIN (100 3875) $PN 2
J 0
(85 3890);
DISPLAY 0.787234 (85 3890);
PAINT MONO (85 3890);
FORCEPROP 2 LAST CDS_LIB pure_quanta
J 0
(0 3875);
DISPLAY INVISIBLE (0 3875);
FORCEPROP 1 LAST PACK_TYPE C0201
J 1
(0 3675);
DISPLAY 0.978723 (0 3675);
DISPLAY INVISIBLE (0 3675);
FORCEPROP 1 LAST TOLERANCE 10%
J 2
(0 3725);
DISPLAY 0.978723 (0 3725);
DISPLAY INVISIBLE (0 3725);
FORCEPROP 1 LAST VOLTAGE 6.3V
J 0
(0 3775);
DISPLAY 0.978723 (0 3775);
DISPLAY INVISIBLE (0 3775);
FORCEPROP 1 LAST PATH I55
J 0
(0 4075);
DISPLAY 0.978723 (0 4075);
PAINT WHITE (0 4075);
DISPLAY INVISIBLE (0 4075);
FORCEPROP 0 LAST CDS_LOCATION C2291
J 0
(-125 3925);
DISPLAY 1.021277 (-125 3925);
DISPLAY INVISIBLE (-125 3925);
FORCEPROP 0 LAST $SEC 1
J 0
(225 3925);
DISPLAY 0.680851 (225 3925);
PAINT MONO (225 3925);
DISPLAY INVISIBLE (225 3925);
FORCEPROP 0 LAST CDS_SEC 1
J 0
(-125 3925);
DISPLAY 1.021277 (-125 3925);
DISPLAY INVISIBLE (-125 3925);
FORCEADD Q_CAP..2
(0 4025);
FORCEPROP 1 LAST PART_NUMBER CH4101KEE01
J 1
(0 4075);
DISPLAY 0.978723 (0 4075);
DISPLAY INVISIBLE (0 4075);
FORCEPROP 1 LAST MATERIAL X6S
J 0
(75 4075);
DISPLAY 0.638298 (75 4075);
FORCEPROP 1 LAST VALUE 0.1UF
J 2
(-150 4025);
DISPLAY 0.638298 (-150 4025);
FORCEPROP 1 LAST $LOCATION C2290
J 1
(225 4025);
DISPLAY 0.638298 (225 4025);
FORCEPROP 1 LASTPIN (-100 4025) $PN 1
J 0
(-110 4040);
DISPLAY 0.787234 (-110 4040);
PAINT MONO (-110 4040);
FORCEPROP 1 LASTPIN (100 4025) $PN 2
J 0
(85 4040);
DISPLAY 0.787234 (85 4040);
PAINT MONO (85 4040);
FORCEPROP 1 LAST VOLTAGE 6.3V
J 0
(0 3925);
DISPLAY 0.978723 (0 3925);
DISPLAY INVISIBLE (0 3925);
FORCEPROP 1 LAST TOLERANCE 10%
J 2
(0 3875);
DISPLAY 0.978723 (0 3875);
DISPLAY INVISIBLE (0 3875);
FORCEPROP 1 LAST PACK_TYPE C0201
J 1
(0 3825);
DISPLAY 0.978723 (0 3825);
DISPLAY INVISIBLE (0 3825);
FORCEPROP 2 LAST CDS_LIB pure_quanta
J 0
(0 4025);
DISPLAY INVISIBLE (0 4025);
FORCEPROP 1 LAST PATH I56
J 0
(0 4225);
DISPLAY 0.978723 (0 4225);
PAINT WHITE (0 4225);
DISPLAY INVISIBLE (0 4225);
FORCEPROP 0 LAST CDS_LOCATION C2290
J 0
(-125 4075);
DISPLAY 1.021277 (-125 4075);
DISPLAY INVISIBLE (-125 4075);
FORCEPROP 0 LAST $SEC 1
J 0
(75 4125);
DISPLAY 0.680851 (75 4125);
PAINT MONO (75 4125);
DISPLAY INVISIBLE (75 4125);
FORCEPROP 0 LAST CDS_SEC 1
J 0
(-125 4075);
DISPLAY 1.021277 (-125 4075);
DISPLAY INVISIBLE (-125 4075);
FORCEADD Q_CAP..2
(0 4075);
FORCEPROP 1 LAST PART_NUMBER CH4101KEE01
J 1
(0 4225);
DISPLAY 0.638298 (0 4225);
DISPLAY INVISIBLE (0 4225);
FORCEPROP 1 LAST VALUE 0.1UF
J 2
(-150 4075);
DISPLAY 0.638298 (-150 4075);
FORCEPROP 1 LAST MATERIAL X6S
J 0
(75 4025);
DISPLAY 0.638298 (75 4025);
FORCEPROP 1 LAST TOLERANCE 10%
J 2
(50 4175);
DISPLAY 0.638298 (50 4175);
FORCEPROP 1 LAST PACK_TYPE C0201
J 1
(-150 4175);
DISPLAY 0.638298 (-150 4175);
FORCEPROP 1 LAST VOLTAGE 6.3V
J 0
(100 4175);
DISPLAY 0.638298 (100 4175);
FORCEPROP 1 LAST $LOCATION C2289
J 1
(225 4075);
DISPLAY 0.638298 (225 4075);
FORCEPROP 1 LASTPIN (-100 4075) $PN 1
J 0
(-110 4090);
DISPLAY 0.787234 (-110 4090);
PAINT MONO (-110 4090);
FORCEPROP 1 LASTPIN (100 4075) $PN 2
J 0
(85 4090);
DISPLAY 0.787234 (85 4090);
PAINT MONO (85 4090);
FORCEPROP 2 LAST CDS_LIB pure_quanta
J 0
(0 4075);
DISPLAY INVISIBLE (0 4075);
FORCEPROP 1 LAST PATH I57
J 0
(0 4275);
DISPLAY 0.978723 (0 4275);
PAINT WHITE (0 4275);
DISPLAY INVISIBLE (0 4275);
FORCEPROP 0 LAST CDS_LOCATION C2289
J 0
(-125 4125);
DISPLAY 1.021277 (-125 4125);
DISPLAY INVISIBLE (-125 4125);
FORCEPROP 0 LAST $SEC 1
J 0
(0 4275);
DISPLAY 0.680851 (0 4275);
PAINT MONO (0 4275);
DISPLAY INVISIBLE (0 4275);
FORCEPROP 0 LAST CDS_SEC 1
J 0
(-125 4125);
DISPLAY 1.021277 (-125 4125);
DISPLAY INVISIBLE (-125 4125);
FORCEADD OFFPAGE..2
(1075 3825);
FORCEPROP 2 LAST $XR0 181 
J 0
(1264 3825);
DISPLAY 0.638298 (1264 3825);
PAINT MONO (1264 3825);
FORCEPROP 2 LAST CDS_LIB standard
J 2
(1075 3825);
DISPLAY INVISIBLE (1075 3825);
FORCEPROP 1 LAST OFFPAGE TRUE
J 0
(1400 3700);
DISPLAY 0.872340 (1400 3700);
PAINT AQUA (1400 3700);
DISPLAY INVISIBLE (1400 3700);
FORCEPROP 1 LAST COMMENT_BODY TRUE
J 0
(1030 3730);
DISPLAY 0.872340 (1030 3730);
PAINT GREEN (1030 3730);
DISPLAY INVISIBLE (1030 3730);
FORCEPROP 2 LAST PATH I58
J 0
(1275 3875);
DISPLAY 1.021277 (1275 3875);
DISPLAY INVISIBLE (1275 3875);
FORCEADD OFFPAGE..2
(1075 3875);
FORCEPROP 2 LAST $XR0 181 
J 0
(1264 3875);
DISPLAY 0.638298 (1264 3875);
PAINT MONO (1264 3875);
FORCEPROP 2 LAST CDS_LIB standard
J 0
(1075 3875);
DISPLAY INVISIBLE (1075 3875);
FORCEPROP 1 LAST OFFPAGE TRUE
J 0
(1400 3750);
DISPLAY 0.872340 (1400 3750);
PAINT AQUA (1400 3750);
DISPLAY INVISIBLE (1400 3750);
FORCEPROP 1 LAST COMMENT_BODY TRUE
J 0
(1030 3780);
DISPLAY 0.872340 (1030 3780);
PAINT GREEN (1030 3780);
DISPLAY INVISIBLE (1030 3780);
FORCEPROP 2 LAST PATH I59
J 0
(1275 3925);
DISPLAY 1.021277 (1275 3925);
DISPLAY INVISIBLE (1275 3925);
FORCEADD Q_RES..2
(-4150 -700);
FORCEPROP 1 LAST PART_NUMBER CS36802FB04
J 0
(-4110 -825);
DISPLAY 0.638298 (-4110 -825);
DISPLAY INVISIBLE (-4110 -825);
FORCEPROP 1 LAST PACK_TYPE 0402LF
J 0
(-4110 -875);
DISPLAY 0.638298 (-4110 -875);
FORCEPROP 1 LAST VALUE 68K
J 0
(-4105 -625);
DISPLAY 0.638298 (-4105 -625);
FORCEPROP 1 LAST TOLERANCE 1%
J 0
(-4105 -675);
DISPLAY 0.638298 (-4105 -675);
FORCEPROP 1 LAST WATTAGE 1/16W
J 0
(-4110 -725);
DISPLAY 0.638298 (-4110 -725);
FORCEPROP 1 LAST MATERIAL CHIP
J 0
(-4110 -775);
DISPLAY 0.638298 (-4110 -775);
FORCEPROP 1 LAST LOCATION R4282
J 0
(-4105 -575);
DISPLAY 0.978723 (-4105 -575);
FORCEPROP 1 LASTPIN (-4150 -600) $PN 1
J 0
(-4145 -638);
DISPLAY 0.787234 (-4145 -638);
PAINT MONO (-4145 -638);
FORCEPROP 1 LASTPIN (-4150 -800) $PN 2
J 0
(-4145 -790);
DISPLAY 0.787234 (-4145 -790);
PAINT MONO (-4145 -790);
FORCEPROP 2 LAST CDS_LIB pure_quanta
J 0
(-4150 -700);
DISPLAY INVISIBLE (-4150 -700);
FORCEPROP 1 LAST PATH I6
J 0
(-4100 -525);
DISPLAY 0.978723 (-4100 -525);
PAINT WHITE (-4100 -525);
DISPLAY INVISIBLE (-4100 -525);
FORCEPROP 0 LAST $SEC 1
J 0
(-4100 -525);
DISPLAY 0.680851 (-4100 -525);
PAINT MONO (-4100 -525);
DISPLAY INVISIBLE (-4100 -525);
FORCEPROP 0 LAST CDS_SEC 1
J 0
(-4100 -525);
DISPLAY 1.021277 (-4100 -525);
DISPLAY INVISIBLE (-4100 -525);
FORCEADD OFFPAGE..2
(1075 4025);
FORCEPROP 2 LAST $XR0 240 
J 0
(1264 4025);
DISPLAY 0.638298 (1264 4025);
PAINT MONO (1264 4025);
FORCEPROP 2 LAST CDS_LIB standard
J 0
(1075 4025);
DISPLAY INVISIBLE (1075 4025);
FORCEPROP 1 LAST OFFPAGE TRUE
J 0
(1400 3900);
DISPLAY 0.872340 (1400 3900);
PAINT AQUA (1400 3900);
DISPLAY INVISIBLE (1400 3900);
FORCEPROP 1 LAST COMMENT_BODY TRUE
J 0
(1030 3930);
DISPLAY 0.872340 (1030 3930);
PAINT GREEN (1030 3930);
DISPLAY INVISIBLE (1030 3930);
FORCEPROP 2 LAST PATH I60
J 0
(1275 4075);
DISPLAY 1.021277 (1275 4075);
DISPLAY INVISIBLE (1275 4075);
FORCEADD OFFPAGE..2
(1075 4075);
FORCEPROP 2 LAST $XR0 240 
J 0
(1264 4075);
DISPLAY 0.638298 (1264 4075);
PAINT MONO (1264 4075);
FORCEPROP 2 LAST CDS_LIB standard
J 2
(1075 4075);
DISPLAY INVISIBLE (1075 4075);
FORCEPROP 1 LAST OFFPAGE TRUE
J 0
(1400 3950);
DISPLAY 0.872340 (1400 3950);
PAINT AQUA (1400 3950);
DISPLAY INVISIBLE (1400 3950);
FORCEPROP 1 LAST COMMENT_BODY TRUE
J 0
(1030 3980);
DISPLAY 0.872340 (1030 3980);
PAINT GREEN (1030 3980);
DISPLAY INVISIBLE (1030 3980);
FORCEPROP 2 LAST PATH I61
J 0
(1275 4125);
DISPLAY 1.021277 (1275 4125);
DISPLAY INVISIBLE (1275 4125);
FORCEADD UNIVERSAL_GND..1
(2000 2050);
FORCEPROP 3 LASTPIN (2000 2100) SIG_NAME GND\g
J 0
(2010 2110);
DISPLAY 0.659574 (2010 2110);
PAINT MONO (2010 2110);
DISPLAY INVISIBLE (2010 2110);
FORCEPROP 2 LAST CDS_LIB logical_power
J 0
(2000 2050);
PAINT MONO (2000 2050);
DISPLAY INVISIBLE (2000 2050);
FORCEPROP 1 LAST HDL_POWER GND
J 1
(2025 1975);
DISPLAY 0.872340 (2025 1975);
PAINT GREEN (2025 1975);
DISPLAY INVISIBLE (2025 1975);
FORCEPROP 2 LAST ROOM IO_SLOT
J 1
(1775 2125);
DISPLAY 0.744681 (1775 2125);
DISPLAY INVISIBLE (1775 2125);
FORCEPROP 1 LAST PATH I62
J 0
(2075 2050);
DISPLAY 0.872340 (2075 2050);
PAINT AQUA (2075 2050);
DISPLAY INVISIBLE (2075 2050);
FORCEADD Q_RES..2
(2000 2275);
FORCEPROP 1 LAST PART_NUMBER CS24702FB06
J 0
(2040 2150);
DISPLAY 0.787234 (2040 2150);
DISPLAY INVISIBLE (2040 2150);
FORCEPROP 1 LAST MATERIAL EMPTY
J 0
(2040 2200);
DISPLAY 0.787234 (2040 2200);
PAINT RED (2040 2200);
FORCEPROP 1 LAST WATTAGE 1/16W
J 0
(2040 2250);
DISPLAY 0.787234 (2040 2250);
FORCEPROP 1 LAST VALUE 4.7K
J 0
(2045 2350);
DISPLAY 0.787234 (2045 2350);
FORCEPROP 1 LAST TOLERANCE 1%
J 0
(2045 2300);
DISPLAY 0.787234 (2045 2300);
FORCEPROP 1 LAST PACK_TYPE 0402LF
J 0
(2040 2100);
DISPLAY 0.787234 (2040 2100);
FORCEPROP 1 LAST $LOCATION R4292
J 0
(2045 2400);
DISPLAY 0.978723 (2045 2400);
FORCEPROP 1 LASTPIN (2000 2375) $PN 1
J 0
(2005 2337);
DISPLAY 0.787234 (2005 2337);
FORCEPROP 1 LASTPIN (2000 2175) $PN 2
J 0
(2005 2185);
DISPLAY 0.787234 (2005 2185);
FORCEPROP 2 LAST CDS_LIB pure_quanta
J 0
(2000 2275);
PAINT MONO (2000 2275);
DISPLAY INVISIBLE (2000 2275);
FORCEPROP 1 LAST PATH I63
J 0
(2050 2450);
DISPLAY 0.978723 (2050 2450);
PAINT WHITE (2050 2450);
DISPLAY INVISIBLE (2050 2450);
FORCEPROP 2 LAST CDS_LOCATION R4292
J 0
(2050 2500);
DISPLAY 1.021277 (2050 2500);
DISPLAY INVISIBLE (2050 2500);
FORCEPROP 2 LAST $SEC 1
J 0
(2050 2500);
DISPLAY 0.680851 (2050 2500);
PAINT MONO (2050 2500);
DISPLAY INVISIBLE (2050 2500);
FORCEPROP 2 LAST CDS_SEC 1
J 0
(2050 2500);
DISPLAY 1.021277 (2050 2500);
DISPLAY INVISIBLE (2050 2500);
FORCEADD OFFPAGE..2
(2725 2550);
FORCEPROP 2 LAST $XR0 169 
J 0
(2914 2550);
DISPLAY 0.638298 (2914 2550);
PAINT MONO (2914 2550);
FORCEPROP 2 LAST CDS_LIB standard
J 0
(2725 2550);
PAINT MONO (2725 2550);
DISPLAY INVISIBLE (2725 2550);
FORCEPROP 1 LAST OFFPAGE TRUE
J 0
(3050 2425);
DISPLAY 0.872340 (3050 2425);
PAINT GREEN (3050 2425);
DISPLAY INVISIBLE (3050 2425);
FORCEPROP 1 LAST COMMENT_BODY TRUE
J 0
(2680 2455);
DISPLAY 0.872340 (2680 2455);
PAINT GREEN (2680 2455);
DISPLAY INVISIBLE (2680 2455);
FORCEPROP 2 LAST PATH I64
J 0
(2925 2600);
DISPLAY 1.021277 (2925 2600);
DISPLAY INVISIBLE (2925 2600);
FORCEADD Q_RES..2
(2000 2800);
FORCEPROP 1 LAST PART_NUMBER CS24702FB06
J 0
(2040 2675);
DISPLAY 0.787234 (2040 2675);
DISPLAY INVISIBLE (2040 2675);
FORCEPROP 1 LAST PACK_TYPE 0402LF
J 0
(2040 2625);
DISPLAY 0.787234 (2040 2625);
FORCEPROP 1 LAST TOLERANCE 1%
J 0
(2045 2825);
DISPLAY 0.787234 (2045 2825);
FORCEPROP 1 LAST VALUE 4.7K
J 0
(2045 2875);
DISPLAY 0.787234 (2045 2875);
FORCEPROP 1 LAST MATERIAL EMPTY
J 0
(2040 2725);
DISPLAY 0.787234 (2040 2725);
PAINT RED (2040 2725);
FORCEPROP 1 LAST WATTAGE 1/16W
J 0
(2040 2775);
DISPLAY 0.787234 (2040 2775);
FORCEPROP 1 LAST $LOCATION R4291
J 0
(2045 2925);
DISPLAY 0.978723 (2045 2925);
FORCEPROP 1 LASTPIN (2000 2900) $PN 1
J 0
(2005 2862);
DISPLAY 0.787234 (2005 2862);
PAINT MONO (2005 2862);
FORCEPROP 1 LASTPIN (2000 2700) $PN 2
J 0
(2005 2710);
DISPLAY 0.787234 (2005 2710);
PAINT MONO (2005 2710);
FORCEPROP 2 LAST CDS_LIB pure_quanta
J 0
(2000 2800);
DISPLAY INVISIBLE (2000 2800);
FORCEPROP 1 LAST PATH I65
J 0
(2050 2975);
DISPLAY 0.978723 (2050 2975);
PAINT WHITE (2050 2975);
DISPLAY INVISIBLE (2050 2975);
FORCEPROP 0 LAST CDS_LOCATION R4291
J 0
(2050 2975);
DISPLAY 1.021277 (2050 2975);
DISPLAY INVISIBLE (2050 2975);
FORCEPROP 0 LAST $SEC 1
J 0
(2050 2975);
DISPLAY 0.680851 (2050 2975);
PAINT MONO (2050 2975);
DISPLAY INVISIBLE (2050 2975);
FORCEPROP 0 LAST CDS_SEC 1
J 0
(2050 2975);
DISPLAY 1.021277 (2050 2975);
DISPLAY INVISIBLE (2050 2975);
FORCEADD UNIVERSAL_POWER..1
(2000 3100);
FORCEPROP 3 LASTPIN (2000 3050) SIG_NAME P3V3_AUX\g
J 0
(2010 3060);
DISPLAY 0.659574 (2010 3060);
PAINT MONO (2010 3060);
DISPLAY INVISIBLE (2010 3060);
FORCEPROP 1 LAST HDL_POWER P3V3_AUX
J 1
(2000 3150);
DISPLAY 0.872340 (2000 3150);
PAINT GREEN (2000 3150);
FORCEPROP 2 LAST CDS_LIB logical_power
J 0
(2000 3100);
PAINT MONO (2000 3100);
DISPLAY INVISIBLE (2000 3100);
FORCEPROP 1 LAST PATH I66
J 0
(2050 3125);
DISPLAY 0.872340 (2050 3125);
PAINT AQUA (2050 3125);
DISPLAY INVISIBLE (2050 3125);
FORCEADD UNIVERSAL_GND..1
(2000 3425);
FORCEPROP 3 LASTPIN (2000 3475) SIG_NAME GND\g
J 0
(2010 3485);
DISPLAY 0.659574 (2010 3485);
PAINT MONO (2010 3485);
DISPLAY INVISIBLE (2010 3485);
FORCEPROP 2 LAST CDS_LIB logical_power
J 0
(2000 3425);
PAINT MONO (2000 3425);
DISPLAY INVISIBLE (2000 3425);
FORCEPROP 1 LAST HDL_POWER GND
J 1
(2025 3350);
DISPLAY 0.872340 (2025 3350);
PAINT GREEN (2025 3350);
DISPLAY INVISIBLE (2025 3350);
FORCEPROP 2 LAST ROOM IO_SLOT
J 1
(1775 3500);
DISPLAY 0.744681 (1775 3500);
DISPLAY INVISIBLE (1775 3500);
FORCEPROP 1 LAST PATH I67
J 0
(2075 3425);
DISPLAY 0.872340 (2075 3425);
PAINT AQUA (2075 3425);
DISPLAY INVISIBLE (2075 3425);
FORCEADD Q_RES..2
(2000 3650);
FORCEPROP 1 LAST PART_NUMBER CS24702FB06
J 0
(2040 3525);
DISPLAY 0.787234 (2040 3525);
DISPLAY INVISIBLE (2040 3525);
FORCEPROP 1 LAST MATERIAL EMPTY
J 0
(2040 3575);
DISPLAY 0.787234 (2040 3575);
PAINT RED (2040 3575);
FORCEPROP 1 LAST PACK_TYPE 0402LF
J 0
(2040 3475);
DISPLAY 0.787234 (2040 3475);
FORCEPROP 1 LAST WATTAGE 1/16W
J 0
(2040 3625);
DISPLAY 0.787234 (2040 3625);
FORCEPROP 1 LAST VALUE 4.7K
J 0
(2045 3725);
DISPLAY 0.787234 (2045 3725);
FORCEPROP 1 LAST TOLERANCE 1%
J 0
(2045 3675);
DISPLAY 0.787234 (2045 3675);
FORCEPROP 1 LAST $LOCATION R4290
J 0
(2045 3775);
DISPLAY 0.978723 (2045 3775);
FORCEPROP 1 LASTPIN (2000 3750) $PN 1
J 0
(2005 3712);
DISPLAY 0.787234 (2005 3712);
FORCEPROP 1 LASTPIN (2000 3550) $PN 2
J 0
(2005 3560);
DISPLAY 0.787234 (2005 3560);
FORCEPROP 2 LAST CDS_LIB pure_quanta
J 0
(2000 3650);
PAINT MONO (2000 3650);
DISPLAY INVISIBLE (2000 3650);
FORCEPROP 1 LAST PATH I68
J 0
(2050 3825);
DISPLAY 0.978723 (2050 3825);
PAINT WHITE (2050 3825);
DISPLAY INVISIBLE (2050 3825);
FORCEPROP 2 LAST CDS_LOCATION R4290
J 0
(2050 3875);
DISPLAY 1.021277 (2050 3875);
DISPLAY INVISIBLE (2050 3875);
FORCEPROP 2 LAST $SEC 1
J 0
(2050 3875);
DISPLAY 0.680851 (2050 3875);
PAINT MONO (2050 3875);
DISPLAY INVISIBLE (2050 3875);
FORCEPROP 2 LAST CDS_SEC 1
J 0
(2050 3875);
DISPLAY 1.021277 (2050 3875);
DISPLAY INVISIBLE (2050 3875);
FORCEADD Q_RES..2
(2000 4175);
FORCEPROP 1 LAST PART_NUMBER CS24702FB06
J 0
(2040 4050);
DISPLAY 0.787234 (2040 4050);
DISPLAY INVISIBLE (2040 4050);
FORCEPROP 1 LAST MATERIAL EMPTY
J 0
(2040 4100);
DISPLAY 0.787234 (2040 4100);
PAINT RED (2040 4100);
FORCEPROP 1 LAST PACK_TYPE 0402LF
J 0
(2040 4000);
DISPLAY 0.787234 (2040 4000);
FORCEPROP 1 LAST WATTAGE 1/16W
J 0
(2040 4150);
DISPLAY 0.787234 (2040 4150);
FORCEPROP 1 LAST TOLERANCE 1%
J 0
(2045 4200);
DISPLAY 0.787234 (2045 4200);
FORCEPROP 1 LAST VALUE 4.7K
J 0
(2045 4250);
DISPLAY 0.787234 (2045 4250);
FORCEPROP 1 LAST $LOCATION R4289
J 0
(2045 4300);
DISPLAY 0.978723 (2045 4300);
FORCEPROP 1 LASTPIN (2000 4275) $PN 1
J 0
(2005 4237);
DISPLAY 0.787234 (2005 4237);
PAINT MONO (2005 4237);
FORCEPROP 1 LASTPIN (2000 4075) $PN 2
J 0
(2005 4085);
DISPLAY 0.787234 (2005 4085);
PAINT MONO (2005 4085);
FORCEPROP 2 LAST CDS_LIB pure_quanta
J 0
(2000 4175);
DISPLAY INVISIBLE (2000 4175);
FORCEPROP 1 LAST PATH I69
J 0
(2050 4350);
DISPLAY 0.978723 (2050 4350);
PAINT WHITE (2050 4350);
DISPLAY INVISIBLE (2050 4350);
FORCEPROP 0 LAST CDS_LOCATION R4289
J 0
(2050 4350);
DISPLAY 1.021277 (2050 4350);
DISPLAY INVISIBLE (2050 4350);
FORCEPROP 0 LAST $SEC 1
J 0
(2050 4350);
DISPLAY 0.680851 (2050 4350);
PAINT MONO (2050 4350);
DISPLAY INVISIBLE (2050 4350);
FORCEPROP 0 LAST CDS_SEC 1
J 0
(2050 4350);
DISPLAY 1.021277 (2050 4350);
DISPLAY INVISIBLE (2050 4350);
FORCEADD Q_RES..2
(-4150 -125);
FORCEPROP 1 LAST PART_NUMBER CS21002FB06
J 0
(-4110 -250);
DISPLAY 0.638298 (-4110 -250);
DISPLAY INVISIBLE (-4110 -250);
FORCEPROP 1 LAST WATTAGE 1/16W
J 0
(-4110 -150);
DISPLAY 0.638298 (-4110 -150);
FORCEPROP 1 LAST TOLERANCE 1%
J 0
(-4105 -100);
DISPLAY 0.638298 (-4105 -100);
FORCEPROP 1 LAST VALUE 1K
J 0
(-4105 -50);
DISPLAY 0.638298 (-4105 -50);
FORCEPROP 1 LAST MATERIAL EMPTY
J 0
(-4110 -200);
DISPLAY 0.638298 (-4110 -200);
PAINT RED (-4110 -200);
FORCEPROP 1 LAST PACK_TYPE 0402LF
J 0
(-4110 -300);
DISPLAY 0.638298 (-4110 -300);
FORCEPROP 1 LAST $LOCATION R4281
J 0
(-4105 0);
DISPLAY 0.978723 (-4105 0);
FORCEPROP 1 LASTPIN (-4150 -25) $PN 1
J 0
(-4145 -63);
DISPLAY 0.787234 (-4145 -63);
PAINT MONO (-4145 -63);
FORCEPROP 1 LASTPIN (-4150 -225) $PN 2
J 0
(-4145 -215);
DISPLAY 0.787234 (-4145 -215);
PAINT MONO (-4145 -215);
FORCEPROP 2 LAST CDS_LIB pure_quanta
J 0
(-4150 -125);
DISPLAY INVISIBLE (-4150 -125);
FORCEPROP 1 LAST PATH I7
J 0
(-4100 50);
DISPLAY 0.978723 (-4100 50);
PAINT WHITE (-4100 50);
DISPLAY INVISIBLE (-4100 50);
FORCEPROP 0 LAST CDS_LOCATION R4281
J 0
(-4100 50);
DISPLAY 1.021277 (-4100 50);
DISPLAY INVISIBLE (-4100 50);
FORCEPROP 0 LAST $SEC 1
J 0
(-4100 50);
DISPLAY 0.680851 (-4100 50);
PAINT MONO (-4100 50);
DISPLAY INVISIBLE (-4100 50);
FORCEPROP 0 LAST CDS_SEC 1
J 0
(-4100 50);
DISPLAY 1.021277 (-4100 50);
DISPLAY INVISIBLE (-4100 50);
FORCEADD UNIVERSAL_POWER..1
(2000 4475);
FORCEPROP 3 LASTPIN (2000 4425) SIG_NAME P3V3_AUX\g
J 0
(2010 4435);
DISPLAY 0.659574 (2010 4435);
PAINT MONO (2010 4435);
DISPLAY INVISIBLE (2010 4435);
FORCEPROP 1 LAST HDL_POWER P3V3_AUX
J 1
(2000 4525);
DISPLAY 0.872340 (2000 4525);
PAINT GREEN (2000 4525);
FORCEPROP 2 LAST CDS_LIB logical_power
J 0
(2000 4475);
PAINT MONO (2000 4475);
DISPLAY INVISIBLE (2000 4475);
FORCEPROP 1 LAST PATH I70
J 0
(2050 4500);
DISPLAY 0.872340 (2050 4500);
PAINT AQUA (2050 4500);
DISPLAY INVISIBLE (2050 4500);
FORCEADD OFFPAGE..2
(2725 3925);
FORCEPROP 2 LAST $XR0 169 
J 0
(2914 3925);
DISPLAY 0.638298 (2914 3925);
PAINT MONO (2914 3925);
FORCEPROP 2 LAST CDS_LIB standard
J 0
(2725 3925);
PAINT MONO (2725 3925);
DISPLAY INVISIBLE (2725 3925);
FORCEPROP 1 LAST OFFPAGE TRUE
J 0
(3050 3800);
DISPLAY 0.872340 (3050 3800);
PAINT GREEN (3050 3800);
DISPLAY INVISIBLE (3050 3800);
FORCEPROP 1 LAST COMMENT_BODY TRUE
J 0
(2680 3830);
DISPLAY 0.872340 (2680 3830);
PAINT GREEN (2680 3830);
DISPLAY INVISIBLE (2680 3830);
FORCEPROP 2 LAST PATH I71
J 0
(2925 3975);
DISPLAY 1.021277 (2925 3975);
DISPLAY INVISIBLE (2925 3975);
FORCEADD OFFPAGE..2
(-3550 -425);
FORCEPROP 2 LAST $XR0 169 
J 0
(-3361 -425);
DISPLAY 0.638298 (-3361 -425);
PAINT MONO (-3361 -425);
FORCEPROP 2 LAST CDS_LIB standard
J 0
(-3550 -425);
DISPLAY INVISIBLE (-3550 -425);
FORCEPROP 1 LAST OFFPAGE TRUE
J 0
(-3225 -550);
DISPLAY 0.872340 (-3225 -550);
PAINT GREEN (-3225 -550);
DISPLAY INVISIBLE (-3225 -550);
FORCEPROP 1 LAST COMMENT_BODY TRUE
J 0
(-3595 -520);
DISPLAY 0.872340 (-3595 -520);
PAINT GREEN (-3595 -520);
DISPLAY INVISIBLE (-3595 -520);
FORCEPROP 2 LAST PATH I8
J 0
(-3350 -375);
DISPLAY 1.021277 (-3350 -375);
DISPLAY INVISIBLE (-3350 -375);
FORCEADD OFFPAGE..2
(-3550 -375);
FORCEPROP 2 LAST $XR0 169 
J 0
(-3361 -375);
DISPLAY 0.638298 (-3361 -375);
PAINT MONO (-3361 -375);
FORCEPROP 2 LAST CDS_LIB standard
J 0
(-3550 -375);
DISPLAY INVISIBLE (-3550 -375);
FORCEPROP 1 LAST OFFPAGE TRUE
J 0
(-3225 -500);
DISPLAY 0.872340 (-3225 -500);
PAINT GREEN (-3225 -500);
DISPLAY INVISIBLE (-3225 -500);
FORCEPROP 1 LAST COMMENT_BODY TRUE
J 0
(-3595 -470);
DISPLAY 0.872340 (-3595 -470);
PAINT GREEN (-3595 -470);
DISPLAY INVISIBLE (-3595 -470);
FORCEPROP 2 LAST PATH I9
J 0
(-3350 -325);
DISPLAY 1.021277 (-3350 -325);
DISPLAY INVISIBLE (-3350 -325);
FORCEADD QUANTA_TITLE_BLOCK_C..1
(3425 -1425);
FORCEPROP 0 LAST CDS_CON_LAST_MODIFIED Fri Aug 25 14:02:39 2023
J 0
(1540 -1410);
DISPLAY INVISIBLE (1540 -1410);
FORCEPROP 1 LAST CUSTOM_TXT_CDS <CON_LAST_MODIFIED>
J 0
(1540 -1410);
DISPLAY 0.978723 (1540 -1410);
FORCEPROP 2 LAST CUSTOM_TXT_CDS <XR_PAGE_TITLE>
J 0
(-4465 3825);
DISPLAY 0.638298 (-4465 3825);
PAINT PINK (-4465 3825);
DISPLAY INVISIBLE (-4465 3825);
FORCEPROP 1 LAST CUSTOM_TXT_CDS <NAME_2>
J 0
(250 -1375);
FORCEPROP 1 LAST CUSTOM_TXT_CDS <NAME_1>
J 0
(250 -1250);
FORCEPROP 1 LAST CUSTOM_TXT_CDS <Q_NUMBER>
J 0
(2022 -1322);
DISPLAY 1.212766 (2022 -1322);
FORCEPROP 1 LAST CUSTOM_TXT_CDS <Q_PROJ>
J 0
(1043 -1323);
DISPLAY 1.212766 (1043 -1323);
FORCEPROP 1 LAST CUSTOM_TXT_CDS <Q_REV>
J 0
(3241 -1322);
DISPLAY 1.212766 (3241 -1322);
FORCEPROP 1 LAST CUSTOM_TXT_CDS <CON_PAGE_NUM> OF <CON_TOTAL_PAGES>
J 0
(2979 -1407);
DISPLAY 0.978723 (2979 -1407);
FORCEPROP 1 LAST Q_TITLE USB3.0 REDRIVER
J 0
(-5900 -1400);
DISPLAY 2.446809 (-5900 -1400);
PAINT GREEN (-5900 -1400);
FORCEPROP 1 LAST Q_DEPT 
J 1
(-338 -1376);
DISPLAY 1.957447 (-338 -1376);
PAINT GREEN (-338 -1376);
FORCEPROP 2 LAST CDS_XR_PAGE_TITLE CR-169 : @S9S_MB_2U_LIB.S9S_MB_2U(SCH_1):PAGE169
J 0
(-4465 3825);
DISPLAY 0.638298 (-4465 3825);
PAINT PINK (-4465 3825);
DISPLAY INVISIBLE (-4465 3825);
FORCEPROP 1 LAST COMMENT_BODY TRUE
J 0
(3437 -1438);
DISPLAY 0.978723 (3437 -1438);
PAINT GREEN (3437 -1438);
DISPLAY INVISIBLE (3437 -1438);
FORCEPROP 2 LAST PAGE_BORDER TRUE
J 0
(-4465 3825);
DISPLAY 0.638298 (-4465 3825);
PAINT PINK (-4465 3825);
DISPLAY INVISIBLE (-4465 3825);
FORCEPROP 1 LAST CDS_LMAN_SYM_OUTLINE -9475,6775,100,-125
J 0
(3425 -1425);
DISPLAY 0.468085 (3425 -1425);
PAINT GREEN (3425 -1425);
DISPLAY INVISIBLE (3425 -1425);
FORCEPROP 2 LAST CDS_LIB pure_quanta
J 0
(3425 -1425);
DISPLAY INVISIBLE (3425 -1425);
FORCEADD DNS..2
(-5025 -150);
PAINT RED (-5025 -150);
FORCEPROP 2 LAST CDS_LIB mstr_misc
J 0
(-5025 -150);
DISPLAY INVISIBLE (-5025 -150);
FORCEPROP 1 LAST COMMENT_BODY TRUE
R 1
J 0
(-4950 -375);
DISPLAY 0.872340 (-4950 -375);
PAINT GREEN (-4950 -375);
DISPLAY INVISIBLE (-4950 -375);
FORCEADD DNS..2
(-4150 -150);
PAINT RED (-4150 -150);
FORCEPROP 2 LAST CDS_LIB mstr_misc
J 0
(-4150 -150);
DISPLAY INVISIBLE (-4150 -150);
FORCEPROP 1 LAST COMMENT_BODY TRUE
R 1
J 0
(-4075 -375);
DISPLAY 0.872340 (-4075 -375);
PAINT GREEN (-4075 -375);
DISPLAY INVISIBLE (-4075 -375);
FORCEADD DNS..2
(-5350 1075);
PAINT RED (-5350 1075);
FORCEPROP 2 LAST CDS_LIB mstr_misc
J 0
(-5350 1075);
DISPLAY INVISIBLE (-5350 1075);
FORCEPROP 1 LAST COMMENT_BODY TRUE
R 1
J 0
(-5275 850);
DISPLAY 0.872340 (-5275 850);
PAINT GREEN (-5275 850);
DISPLAY INVISIBLE (-5275 850);
FORCEADD DNS..2
(-5350 1600);
PAINT RED (-5350 1600);
FORCEPROP 2 LAST CDS_LIB mstr_misc
J 0
(-5350 1600);
DISPLAY INVISIBLE (-5350 1600);
FORCEPROP 1 LAST COMMENT_BODY TRUE
R 1
J 0
(-5275 1375);
DISPLAY 0.872340 (-5275 1375);
PAINT GREEN (-5275 1375);
DISPLAY INVISIBLE (-5275 1375);
FORCEADD DNS..2
(-4475 1025);
PAINT RED (-4475 1025);
FORCEPROP 2 LAST CDS_LIB mstr_misc
J 0
(-4475 1025);
DISPLAY INVISIBLE (-4475 1025);
FORCEPROP 1 LAST COMMENT_BODY TRUE
R 1
J 0
(-4400 800);
DISPLAY 0.872340 (-4400 800);
PAINT GREEN (-4400 800);
DISPLAY INVISIBLE (-4400 800);
FORCEADD DNS..2
(-4475 1600);
PAINT RED (-4475 1600);
FORCEPROP 2 LAST CDS_LIB mstr_misc
J 0
(-4475 1600);
DISPLAY INVISIBLE (-4475 1600);
FORCEPROP 1 LAST COMMENT_BODY TRUE
R 1
J 0
(-4400 1375);
DISPLAY 0.872340 (-4400 1375);
PAINT GREEN (-4400 1375);
DISPLAY INVISIBLE (-4400 1375);
FORCEADD DNS..2
(-750 1050);
PAINT RED (-750 1050);
FORCEPROP 2 LAST CDS_LIB mstr_misc
J 0
(-750 1050);
DISPLAY INVISIBLE (-750 1050);
FORCEPROP 1 LAST COMMENT_BODY TRUE
R 1
J 0
(-675 825);
DISPLAY 0.872340 (-675 825);
PAINT GREEN (-675 825);
DISPLAY INVISIBLE (-675 825);
FORCEADD DNS..2
(-750 1575);
PAINT RED (-750 1575);
FORCEPROP 2 LAST CDS_LIB mstr_misc
J 0
(-750 1575);
DISPLAY INVISIBLE (-750 1575);
FORCEPROP 1 LAST COMMENT_BODY TRUE
R 1
J 0
(-675 1350);
DISPLAY 0.872340 (-675 1350);
PAINT GREEN (-675 1350);
DISPLAY INVISIBLE (-675 1350);
FORCEADD DNS..2
(125 1000);
PAINT RED (125 1000);
FORCEPROP 2 LAST CDS_LIB mstr_misc
J 0
(125 1000);
DISPLAY INVISIBLE (125 1000);
FORCEPROP 1 LAST COMMENT_BODY TRUE
R 1
J 0
(200 775);
DISPLAY 0.872340 (200 775);
PAINT GREEN (200 775);
DISPLAY INVISIBLE (200 775);
FORCEADD DNS..2
(125 1575);
PAINT RED (125 1575);
FORCEPROP 2 LAST CDS_LIB mstr_misc
J 0
(125 1575);
DISPLAY INVISIBLE (125 1575);
FORCEPROP 1 LAST COMMENT_BODY TRUE
R 1
J 0
(200 1350);
DISPLAY 0.872340 (200 1350);
PAINT GREEN (200 1350);
DISPLAY INVISIBLE (200 1350);
FORCEADD DNS..2
(2000 2250);
PAINT RED (2000 2250);
FORCEPROP 2 LAST CDS_LIB mstr_misc
J 0
(2000 2250);
DISPLAY INVISIBLE (2000 2250);
FORCEPROP 1 LAST COMMENT_BODY TRUE
R 1
J 0
(2075 2025);
DISPLAY 0.872340 (2075 2025);
PAINT GREEN (2075 2025);
DISPLAY INVISIBLE (2075 2025);
FORCEADD DNS..2
(2000 2775);
PAINT RED (2000 2775);
FORCEPROP 2 LAST CDS_LIB mstr_misc
J 0
(2000 2775);
DISPLAY INVISIBLE (2000 2775);
FORCEPROP 1 LAST COMMENT_BODY TRUE
R 1
J 0
(2075 2550);
DISPLAY 0.872340 (2075 2550);
PAINT GREEN (2075 2550);
DISPLAY INVISIBLE (2075 2550);
FORCEADD DNS..2
(2000 3625);
PAINT RED (2000 3625);
FORCEPROP 2 LAST CDS_LIB mstr_misc
J 0
(2000 3625);
DISPLAY INVISIBLE (2000 3625);
FORCEPROP 1 LAST COMMENT_BODY TRUE
R 1
J 0
(2075 3400);
DISPLAY 0.872340 (2075 3400);
PAINT GREEN (2075 3400);
DISPLAY INVISIBLE (2075 3400);
FORCEADD DNS..2
(2000 4150);
PAINT RED (2000 4150);
FORCEPROP 2 LAST CDS_LIB mstr_misc
J 0
(2000 4150);
DISPLAY INVISIBLE (2000 4150);
FORCEPROP 1 LAST COMMENT_BODY TRUE
R 1
J 0
(2075 3925);
DISPLAY 0.872340 (2075 3925);
PAINT GREEN (2075 3925);
DISPLAY INVISIBLE (2075 3925);
WIRE 16 -1 (-5025 125)(-5025 75);
WIRE 16 -1 (-5350 1875)(-5350 1825);
WIRE 16 -1 (-3650 4750)(-3650 4625);
WIRE 16 -1 (-750 1850)(-750 1800);
WIRE 16 -1 (2000 2900)(2000 3050);
WIRE 16 -1 (2000 4275)(2000 4425);
WIRE 16 -1 (-5025 -950)(-5025 -750);
WIRE 16 -1 (-4150 -950)(-4150 -800);
WIRE 16 -1 (-5350 800)(-5350 1000);
WIRE 16 -1 (-4475 800)(-4475 950);
WIRE 16 -1 (-3850 2650)(-3850 2800);
WIRE 16 -1 (-4250 2650)(-4250 2800);
WIRE 16 -1 (-3025 4075)(-3025 4150);
WIRE 16 -1 (-750 775)(-750 975);
WIRE 16 -1 (-1025 2825)(-1025 3025);
WIRE 16 -1 (125 775)(125 925);
WIRE 16 -1 (2000 2100)(2000 2175);
WIRE 16 -1 (2000 3475)(2000 3550);
WIRE 16 -1 (2000 3750)(2000 3925);
WIRE 16 -1 (2000 3925)(2000 4075);
WIRE 16 -1 (2675 3925)(2000 3925);
FORCEPROP 2 LAST SIG_NAME FM_USB3_1_RXDET_EN
J 0
(2065 3935);
DISPLAY 0.680851 (2065 3935);
PAINT WHITE (2065 3935);
WIRE 16 -1 (2000 2375)(2000 2550);
WIRE 16 -1 (2000 2550)(2000 2700);
WIRE 16 -1 (2000 2550)(2675 2550);
FORCEPROP 2 LAST SIG_NAME FM_USB3_1_EN_N
J 0
(2240 2560);
DISPLAY 0.680851 (2240 2560);
PAINT WHITE (2240 2560);
WIRE 16 -1 (1025 4075)(100 4075);
FORCEPROP 2 LAST SIG_NAME USB3_PCH_TX_BUF_C_DP<4>
J 0
(390 4085);
DISPLAY 0.553191 (390 4085);
PAINT WHITE (390 4085);
WIRE 16 -1 (1025 4025)(100 4025);
FORCEPROP 2 LAST SIG_NAME USB3_PCH_TX_BUF_C_DN<4>
J 0
(390 4035);
DISPLAY 0.553191 (390 4035);
PAINT WHITE (390 4035);
WIRE 16 -1 (1025 3875)(100 3875);
FORCEPROP 2 LAST SIG_NAME USB3_PCH_RX_BUF_DP<4>
J 0
(390 3885);
DISPLAY 0.553191 (390 3885);
PAINT WHITE (390 3885);
WIRE 16 -1 (1025 3825)(100 3825);
FORCEPROP 2 LAST SIG_NAME USB3_PCH_RX_BUF_DN<4>
J 0
(390 3835);
DISPLAY 0.553191 (390 3835);
PAINT WHITE (390 3835);
WIRE 16 -1 (125 1125)(125 1300);
WIRE 16 -1 (125 1300)(575 1300);
FORCEPROP 2 LAST SIG_NAME FM_USB3_1_SWA
J 0
(165 1310);
DISPLAY 0.638298 (165 1310);
PAINT WHITE (165 1310);
WIRE 16 -1 (125 1500)(125 1300);
WIRE 16 -1 (-750 1800)(-750 1700);
WIRE 16 -1 (125 1800)(-750 1800);
WIRE 16 -1 (125 1700)(125 1800);
WIRE 16 -1 (-225 3725)(-1100 3725);
FORCEPROP 2 LAST SIG_NAME FM_USB3_1_RXDET_EN
J 0
(-930 3735);
DISPLAY 0.553191 (-930 3735);
PAINT WHITE (-930 3735);
WIRE 16 -1 (-225 3575)(-1100 3575);
FORCEPROP 2 LAST SIG_NAME FM_USB3_1_EN_N
J 0
(-935 3585);
DISPLAY 0.553191 (-935 3585);
PAINT WHITE (-935 3585);
WIRE 16 -1 (-1100 4075)(-100 4075);
FORCEPROP 2 LAST SIG_NAME USB3_PCH_TX_BUF_DP<4>
J 0
(-935 4085);
DISPLAY 0.553191 (-935 4085);
PAINT WHITE (-935 4085);
WIRE 16 -1 (-1100 4025)(-100 4025);
FORCEPROP 2 LAST SIG_NAME USB3_PCH_TX_BUF_DN<4>
J 0
(-935 4035);
DISPLAY 0.553191 (-935 4035);
PAINT WHITE (-935 4035);
WIRE 16 -1 (-1100 3875)(-100 3875);
FORCEPROP 2 LAST SIG_NAME USB3_PCH_RX_BUF_C_DP<4>
J 0
(-935 3885);
DISPLAY 0.553191 (-935 3885);
PAINT WHITE (-935 3885);
WIRE 16 -1 (-1100 3825)(-100 3825);
FORCEPROP 2 LAST SIG_NAME USB3_PCH_RX_BUF_C_DN<4>
J 0
(-935 3835);
DISPLAY 0.553191 (-935 3835);
PAINT WHITE (-935 3835);
WIRE 16 -1 (-1100 3025)(-1025 3025);
WIRE 16 -1 (-1025 3025)(-1025 3175);
WIRE 16 -1 (-1025 3175)(-1100 3175);
WIRE 16 -1 (-1025 3225)(-1025 3175);
WIRE 16 -1 (-1025 3225)(-1100 3225);
WIRE 16 -1 (-1025 3275)(-1100 3275);
WIRE 16 -1 (-1025 3275)(-1025 3225);
WIRE 16 -1 (-1025 3325)(-1100 3325);
WIRE 16 -1 (-1025 3325)(-1025 3275);
WIRE 16 -1 (-1025 3375)(-1025 3325);
WIRE 16 -1 (-1025 3375)(-1100 3375);
WIRE 16 -1 (-1025 3425)(-1025 3375);
WIRE 16 -1 (-1025 3425)(-1100 3425);
WIRE 16 -1 (-3200 4625)(-3025 4625);
WIRE 16 -1 (-3025 4475)(-3025 4625);
WIRE 16 -1 (-2650 4625)(-2650 4475);
WIRE 16 -1 (-3025 4625)(-2650 4625);
FORCEPROP 2 LAST SIG_NAME P3V3_AUX_USB_BUF
J 0
(-2960 4635);
DISPLAY 0.510638 (-2960 4635);
PAINT WHITE (-2960 4635);
WIRE 16 -1 (-2650 4625)(-2375 4625);
WIRE 16 -1 (-2375 4625)(-2375 4475);
WIRE 16 -1 (-2375 4625)(-2125 4625);
WIRE 16 -1 (-2000 4075)(-2125 4075);
WIRE 16 -1 (-2125 4625)(-2125 4075);
WIRE 16 -1 (-2125 4075)(-2125 4025);
WIRE 16 -1 (-2000 4025)(-2125 4025);
WIRE 16 -1 (-3025 4275)(-3025 4150);
WIRE 16 -1 (-2650 4150)(-3025 4150);
WIRE 16 -1 (-2650 4150)(-2650 4275);
WIRE 16 -1 (-2650 4150)(-2375 4150);
WIRE 16 -1 (-2375 4150)(-2375 4275);
WIRE 16 -1 (-750 1175)(-750 1350);
WIRE 16 -1 (-750 1350)(-750 1500);
WIRE 16 -1 (-750 1350)(575 1350);
FORCEPROP 2 LAST SIG_NAME FM_USB3_1_SWB
J 0
(165 1360);
DISPLAY 0.638298 (165 1360);
PAINT WHITE (165 1360);
WIRE 16 -1 (-2000 3175)(-3650 3175);
FORCEPROP 2 LAST SIG_NAME USB3_PCH_RX_C_DN<4>
J 0
(-2935 3185);
DISPLAY 0.553191 (-2935 3185);
PAINT WHITE (-2935 3185);
WIRE 16 -1 (-2000 3225)(-3650 3225);
FORCEPROP 2 LAST SIG_NAME USB3_PCH_RX_C_DP<4>
J 0
(-2935 3235);
DISPLAY 0.553191 (-2935 3235);
PAINT WHITE (-2935 3235);
WIRE 16 -1 (-2000 3875)(-3200 3875);
FORCEPROP 2 LAST SIG_NAME FM_USB3_1_FGA
J 0
(-2935 3885);
DISPLAY 0.553191 (-2935 3885);
PAINT WHITE (-2935 3885);
WIRE 16 -1 (-2000 3825)(-3200 3825);
FORCEPROP 2 LAST SIG_NAME FM_USB3_1_FGB
J 0
(-2935 3835);
DISPLAY 0.553191 (-2935 3835);
PAINT WHITE (-2935 3835);
WIRE 16 -1 (-2000 3725)(-3200 3725);
FORCEPROP 2 LAST SIG_NAME FM_USB3_1_SWA
J 0
(-2935 3735);
DISPLAY 0.553191 (-2935 3735);
PAINT WHITE (-2935 3735);
WIRE 16 -1 (-2000 3675)(-3200 3675);
FORCEPROP 2 LAST SIG_NAME FM_USB3_1_SWB
J 0
(-2935 3685);
DISPLAY 0.553191 (-2935 3685);
PAINT WHITE (-2935 3685);
WIRE 16 -1 (-2000 3575)(-3200 3575);
FORCEPROP 2 LAST SIG_NAME FM_USB3_1_EQA
J 0
(-2935 3585);
DISPLAY 0.553191 (-2935 3585);
PAINT WHITE (-2935 3585);
WIRE 16 -1 (-2000 3525)(-3200 3525);
FORCEPROP 2 LAST SIG_NAME FM_USB3_1_EQB
J 0
(-2935 3535);
DISPLAY 0.553191 (-2935 3535);
PAINT WHITE (-2935 3535);
WIRE 16 -1 (-2000 3375)(-3200 3375);
FORCEPROP 2 LAST SIG_NAME USB3_PCH_TX_C_DP<4>
J 0
(-2935 3385);
DISPLAY 0.553191 (-2935 3385);
PAINT WHITE (-2935 3385);
WIRE 16 -1 (-2000 3325)(-3200 3325);
FORCEPROP 2 LAST SIG_NAME USB3_PCH_TX_C_DN<4>
J 0
(-2935 3335);
DISPLAY 0.553191 (-2935 3335);
PAINT WHITE (-2935 3335);
WIRE 16 -1 (-3650 4625)(-3400 4625);
WIRE 16 2175 (-4300 2550)(-3075 2550);
WIRE 16 2175 (-3075 3275)(-3075 2550);
WIRE 16 2175 (-4300 3275)(-4300 2550);
WIRE 16 2175 (-4300 3275)(-3075 3275);
WIRE 16 -1 (-4475 1150)(-4475 1325);
WIRE 16 -1 (-4475 1325)(-3975 1325);
FORCEPROP 2 LAST SIG_NAME FM_USB3_1_FGA
J 0
(-4435 1335);
DISPLAY 0.638298 (-4435 1335);
PAINT WHITE (-4435 1335);
WIRE 16 -1 (-4475 1525)(-4475 1325);
WIRE 16 -1 (-3850 3175)(-4850 3175);
FORCEPROP 2 LAST SIG_NAME USB3_PCH_RX_DN<4>
J 0
(-4760 3185);
DISPLAY 0.553191 (-4760 3185);
PAINT WHITE (-4760 3185);
WIRE 16 -1 (-3850 3000)(-3850 3175);
WIRE 16 -1 (-3800 3175)(-3850 3175);
WIRE 16 -1 (-4850 3225)(-4250 3225);
FORCEPROP 2 LAST SIG_NAME USB3_PCH_RX_DP<4>
J 0
(-4760 3235);
DISPLAY 0.553191 (-4760 3235);
PAINT WHITE (-4760 3235);
WIRE 16 -1 (-3800 3225)(-4250 3225);
WIRE 16 -1 (-4250 3000)(-4250 3225);
WIRE 16 -1 (-5350 1825)(-5350 1725);
WIRE 16 -1 (-4475 1825)(-5350 1825);
WIRE 16 -1 (-4475 1725)(-4475 1825);
WIRE 16 -1 (-5350 1200)(-5350 1375);
WIRE 16 -1 (-5350 1375)(-5350 1525);
WIRE 16 -1 (-5350 1375)(-3975 1375);
FORCEPROP 2 LAST SIG_NAME FM_USB3_1_FGB
J 0
(-4435 1385);
DISPLAY 0.638298 (-4435 1385);
PAINT WHITE (-4435 1385);
WIRE 16 -1 (-4150 -600)(-4150 -425);
WIRE 16 -1 (-4150 -425)(-3600 -425);
FORCEPROP 2 LAST SIG_NAME FM_USB3_1_EQB
J 0
(-4110 -415);
DISPLAY 0.638298 (-4110 -415);
PAINT WHITE (-4110 -415);
WIRE 16 -1 (-4150 -225)(-4150 -425);
WIRE 16 -1 (-5025 75)(-5025 -25);
WIRE 16 -1 (-4150 -25)(-4150 75);
WIRE 16 -1 (-4150 75)(-5025 75);
WIRE 16 -1 (-5025 -550)(-5025 -375);
WIRE 16 -1 (-5025 -375)(-5025 -225);
WIRE 16 -1 (-5025 -375)(-3600 -375);
FORCEPROP 2 LAST SIG_NAME FM_USB3_1_EQA
J 0
(-4110 -365);
DISPLAY 0.638298 (-4110 -365);
PAINT WHITE (-4110 -365);
DOT 1 (-5025 -375);
DOT 1 (-5025 75);
DOT 1 (-4150 -425);
DOT 1 (-5350 1375);
DOT 1 (-5350 1825);
DOT 1 (-4475 1325);
DOT 1 (-4250 3225);
DOT 1 (-3850 3175);
DOT 1 (-3025 4150);
DOT 1 (-3025 4625);
DOT 1 (-750 1350);
DOT 1 (-750 1800);
DOT 1 (-2650 4150);
DOT 1 (-2650 4625);
DOT 1 (-2375 4625);
DOT 1 (-2125 4075);
DOT 1 (-1025 3025);
DOT 1 (-1025 3225);
DOT 1 (-1025 3175);
DOT 1 (-1025 3275);
DOT 1 (-1025 3325);
DOT 1 (-1025 3375);
DOT 1 (125 1300);
DOT 1 (2000 2550);
DOT 1 (2000 3925);
FORCENOTE
FROM SCM
(-5675 3175) 0;
DISPLAY LEFT (-5675 3175);
DISPLAY 1.340425 (-5675 3175);
PAINT WHITE (-5675 3175);
FORCENOTE
20220316 ADD R4636,R4637,C2349,C2350
(-4500 2475) 0;
DISPLAY LEFT (-4500 2475);
DISPLAY 0.851064 (-4500 2475);
PAINT WHITE (-4500 2475);
FORCENOTE
FROM PCH
(-4050 3350) 0;
DISPLAY LEFT (-4050 3350);
DISPLAY 1.340425 (-4050 3350);
PAINT WHITE (-4050 3350);
FORCENOTE
20211209 MODIFY FOR GT
(-5750 5050) 0;
DISPLAY LEFT (-5750 5050);
DISPLAY 2.510638 (-5750 5050);
PAINT PINK (-5750 5050);
FORCENOTE
TO SCM
(1425 4025) 0;
DISPLAY LEFT (1425 4025);
DISPLAY 1.340425 (1425 4025);
PAINT WHITE (1425 4025);
FORCENOTE
TO PCH
(1425 3825) 0;
DISPLAY LEFT (1425 3825);
DISPLAY 1.340425 (1425 3825);
PAINT WHITE (1425 3825);
FORCENOTE
$CDS_IMAGE|clipboard_2_1.jpg|1944|484
(-2600 1350) 0;
DISPLAY LEFT (-2600 1350);
FORCENOTE
$CDS_IMAGE|clipboard_0_9.jpg|1963|485
(-2200 -400) 0;
DISPLAY LEFT (-2200 -400);
FORCENOTE
$CDS_IMAGE|clipboard_1_1.jpg|1948|475
(1925 1350) 0;
DISPLAY LEFT (1925 1350);
QUIT
